G04 ================== begin FILE IDENTIFICATION RECORD ==================*
G04 Layout Name:  13919-sa.brd*
G04 Film Name:    TSILK*
G04 File Format:  Gerber RS274X*
G04 File Origin:  Cadence Allegro 16.5-S039*
G04 Origin Date:  Fri Nov 22 15:27:01 2013*
G04 *
G04 Layer:  VIA CLASS/FILMMASKTOP*
G04 Layer:  REF DES/ASSEMBLY_TOP*
G04 Layer:  PACKAGE GEOMETRY/SILKSCREEN_TOP*
G04 Layer:  DRAWING FORMAT/LAYER_PCB_STORY*
G04 Layer:  DRAWING FORMAT/LAYER_SILK_T*
G04 Layer:  BOARD GEOMETRY/SILKSCREEN_TOP*
G04 *
G04 Offset:    (0.00 0.00)*
G04 Mirror:    No*
G04 Mode:      Positive*
G04 Rotation:  0*
G04 FullContactRelief:  No*
G04 UndefLineWidth:     6.00*
G04 ================== end FILE IDENTIFICATION RECORD ====================*
%FSLAX35Y35*MOIN*%
%IR0*IPPOS*OFA0.00000B0.00000*MIA0B0*SFA1.00000B1.00000*%
%ADD10C,.01*%
%ADD11C,.02*%
%ADD12C,.015*%
%ADD13C,.002*%
%ADD14C,.006*%
%ADD15C,.008*%
G75*
%LPD*%
G75*
G36*
G01X28733Y39020D02*
Y34020D01*
X48733D01*
Y39020D01*
X28733D01*
G37*
G54D10*
G01X775591Y373351D02*
G03Y362879I0J-5236D01*
G01Y404847D02*
G03Y394374I0J-5236D01*
G01Y436342D02*
G03Y425869I0J-5236D01*
G01Y467837D02*
G03Y457364I0J-5236D01*
G01Y499332D02*
G03Y488859I0J-5236D01*
G01Y530827D02*
G03Y520355I0J-5236D01*
G54D11*
G01X-67189Y-77263D02*
G02I-12000J0D01*
G01X-72339D02*
G02I-6850J0D01*
G01X-79189Y-93263D02*
Y-61263D01*
G01X-63189Y-77263D02*
X-95189D01*
G01X-63189Y-93263D02*
Y-173263D01*
G01D02*
X1156611D01*
G01X-63189Y-93263D02*
X1156611D01*
G01X-63189Y-128763D02*
X1156611D01*
G01X132030Y60680D02*
X217030D01*
Y44720D01*
X174170D01*
Y25470D01*
X82250D01*
Y45980D01*
X58110D01*
Y60680D01*
X132030D01*
G01X369111Y-93263D02*
Y-173263D01*
G01X506611Y-93263D02*
Y-173263D01*
G01X621611Y-93263D02*
Y-173263D01*
G01X789111Y-93263D02*
Y-173263D01*
G01X959111Y-93263D02*
Y-173263D01*
G01X1156611Y-93263D02*
Y-173263D01*
G01X1184611Y-77263D02*
G02I-12000J0D01*
G01X1179461D02*
G02I-6850J0D01*
G01X1172611Y-93263D02*
Y-61263D01*
G01X1188611Y-77263D02*
X1156611D01*
G54D12*
G01X0Y68504D02*
Y37795D01*
G01Y303544D02*
Y272835D01*
G01Y388485D02*
Y357776D01*
G01Y538583D02*
Y507874D01*
G01Y592816D02*
Y623524D01*
G01X89173Y114567D02*
X58465D01*
G01X89173Y106693D02*
X58465D01*
G01X89173Y341733D02*
X58465D01*
G01X89173Y349607D02*
X58465D01*
G01X89173Y584646D02*
X58465D01*
G01X89173Y576772D02*
X58465D01*
G01X315551Y114567D02*
X284843D01*
G01X315551Y106693D02*
X284843D01*
G01Y341733D02*
X315551D01*
G01X284843Y349607D02*
X315551D01*
G01Y584646D02*
X284843D01*
G01X315551Y576772D02*
X284843D01*
G01X381890Y98524D02*
Y67815D01*
G01X374016Y98524D02*
Y67815D01*
G01Y153445D02*
Y122737D01*
G01X381890Y153445D02*
Y122737D01*
G01X374016Y333563D02*
Y302855D01*
G01X381890Y333563D02*
Y302855D01*
G01Y388485D02*
Y357776D01*
G01X374016Y388485D02*
Y357776D01*
G01X381890Y537894D02*
Y568603D01*
G01X374016Y537894D02*
Y568603D01*
G01Y592816D02*
Y623524D01*
G01X381890Y592816D02*
Y623524D01*
G01X440354Y106693D02*
X471063D01*
G01X440354Y114567D02*
X471063D01*
G01X440354Y341733D02*
X471063D01*
G01X440354Y349607D02*
X471063D01*
G01X440354Y584646D02*
X471063D01*
G01X440354Y576772D02*
X471063D01*
G01X697441Y106693D02*
X666732D01*
G01X697441Y114567D02*
X666732D01*
G01Y341733D02*
X697441D01*
G01X666732Y349607D02*
X697441D01*
G01Y584646D02*
X666732D01*
G01X697441Y576772D02*
X666732D01*
G01X755906Y98524D02*
Y67815D01*
G01Y152756D02*
Y183465D01*
G01Y302855D02*
Y333563D01*
G01Y387796D02*
Y418504D01*
G01Y537894D02*
Y568603D01*
G01Y653544D02*
Y622835D01*
G54D13*
G01X31903Y44110D02*
X31243D01*
G01X31343Y44200D02*
X32003D01*
G01X32093Y44310D02*
X31443D01*
G01X31543Y44400D02*
X32193D01*
G01X32293Y44510D02*
X31633D01*
G01X31733Y44610D02*
X32383D01*
G01X32483Y44700D02*
X31833D01*
G01X31923Y44810D02*
X32583D01*
G01X32673Y44900D02*
X32023D01*
G01X32113Y45010D02*
X32773D01*
G01X32873Y45110D02*
X32213D01*
G01X32313Y45200D02*
X32963D01*
G01X33063Y45310D02*
X32418D01*
G01X32413D02*
X32463D01*
G01X32503Y45400D02*
X32543D01*
G01X32503D02*
X33153D01*
G01X33253Y45510D02*
X32603D01*
G01X32703Y45610D02*
X33353D01*
G01X33453Y45700D02*
X32793D01*
G01X32893Y45810D02*
X33543D01*
G01X33643Y45900D02*
X32983D01*
G01X33083Y46010D02*
X33743D01*
G01X33833Y46110D02*
X33183D01*
G01X33283Y46200D02*
X33933D01*
G01X34023Y46310D02*
X33373D01*
G01X33473Y46400D02*
X34123D01*
G01X34223Y46510D02*
X33563D01*
G01X33663Y46610D02*
X34323D01*
G01X34413Y46700D02*
X33763D01*
G01X33853Y46810D02*
X34513D01*
G01X34703Y47010D02*
X34053D01*
G01X34243Y47200D02*
X34893D01*
G01X29603Y61620D02*
X29633Y61640D01*
G01X29603Y61080D02*
Y61620D01*
G01X29613Y61060D02*
X29603Y61080D01*
G01X29663Y60950D02*
X29613Y61060D01*
G01X29673Y60940D02*
X29663Y60950D01*
G01X34853Y55350D02*
X29673Y60940D01*
G01X29603Y61610D02*
X29663D01*
G01X29603Y61510D02*
X29753D01*
G01X29843Y61400D02*
X29603D01*
G01Y61310D02*
X29943D01*
G01X30033Y61200D02*
X29603D01*
G01Y61110D02*
X30123D01*
G01X30223Y61010D02*
X29633D01*
G01X29703Y60900D02*
X30313D01*
G01X30403Y60810D02*
X29793D01*
G01X29883Y60700D02*
X30493D01*
G01X30593Y60610D02*
X29983D01*
G01X30073Y60510D02*
X30683D01*
G01X30773Y60400D02*
X30163D01*
G01X30253Y60310D02*
X30873D01*
G01X30963Y60200D02*
X30353D01*
G01X30443Y60110D02*
X31053D01*
G01X31153Y60010D02*
X30533D01*
G01X30633Y59900D02*
X31243D01*
G01X31333Y59810D02*
X30723D01*
G01X30813Y59700D02*
X31433D01*
G01X31523Y59610D02*
X30913D01*
G01X31003Y59510D02*
X31613D01*
G01X31713Y59400D02*
X31093D01*
G01X31183Y59310D02*
X31803D01*
G01X31893Y59200D02*
X31283D01*
G01X31373Y59110D02*
X31983D01*
G01X32083Y59010D02*
X31463D01*
G01X31563Y58900D02*
X32173D01*
G01X32263Y58810D02*
X31653D01*
G01X31743Y58700D02*
X32353D01*
G01X32453Y58610D02*
X31843D01*
G01X31933Y58510D02*
X32543D01*
G01X32633Y58400D02*
X32023D01*
G01X32113Y58310D02*
X32733D01*
G01X32823Y58200D02*
X32213D01*
G01X32303Y58110D02*
X32913D01*
G01X33013Y58010D02*
X32393D01*
G01X32483Y57900D02*
X33103D01*
G01X33193Y57810D02*
X32583D01*
G01X32673Y57700D02*
X33293D01*
G01X33383Y57610D02*
X32763D01*
G01X32853Y57510D02*
X33473D01*
G01X33573Y57400D02*
X32953D01*
G01X33043Y57310D02*
X33663D01*
G01X33753Y57200D02*
X33133D01*
G01X33223Y57110D02*
X33853D01*
G01X33943Y57010D02*
X33323D01*
G01X33413Y56900D02*
X34033D01*
G01X34123Y56810D02*
X33503D01*
G01X33603Y56700D02*
X34223D01*
G01X34313Y56610D02*
X33693D01*
G01X33783Y56510D02*
X34403D01*
G01X34503Y56400D02*
X33883D01*
G01X34063Y56200D02*
X35303D01*
G01X35313Y56010D02*
X34253D01*
G01X34003Y58300D02*
X34513D01*
G01X33963Y58260D02*
X34003Y58300D01*
G01X33963Y57800D02*
Y58260D01*
G01X34003Y57760D02*
X33963Y57800D01*
G01Y58200D02*
X44213D01*
G01X44143Y58010D02*
X33963D01*
G01Y57810D02*
X43983D01*
G01X36613Y59110D02*
X35183D01*
G01X34603Y58370D02*
X34513Y58300D01*
G01X34623Y58420D02*
X34603Y58370D01*
G01X34623Y58430D02*
Y58420D01*
G01X34743Y58680D02*
X34623Y58430D01*
G01X34763Y58690D02*
X34743Y58680D01*
G01X35193Y59110D02*
X34763Y58690D01*
G01X34523Y58310D02*
X35253D01*
G01X35363Y58640D02*
X35473Y58710D01*
G01X35193Y58470D02*
X35363Y58640D01*
G01X35173Y58360D02*
X35193Y58470D01*
G01X35263Y58300D02*
X35173Y58360D01*
G01X35333Y58610D02*
X34713D01*
G01X34663Y58510D02*
X35233D01*
G01X35183Y58400D02*
X34613D01*
G01X34873Y58810D02*
X36553D01*
G01Y59010D02*
X35083D01*
G01X35433Y55410D02*
X38663Y51930D01*
G01X35423Y55410D02*
X35433D01*
G01X35383Y55460D02*
X35423Y55410D01*
G01X35353Y55520D02*
X35383Y55460D01*
G01X35173Y57650D02*
X35353Y55520D01*
G01X35273Y57760D02*
X35173Y57650D01*
G01X35693Y51610D02*
X35223D01*
G01X35213Y51810D02*
X35673D01*
G01X35653Y52010D02*
X35193D01*
G01X35173Y52200D02*
X35643D01*
G01X35623Y52400D02*
X35153D01*
G01X35133Y52610D02*
X35603D01*
G01X35593Y52810D02*
X35123D01*
G01X35103Y53010D02*
X35573D01*
G01X35553Y53200D02*
X35083D01*
G01X35073Y53400D02*
X35543D01*
G01X35523Y53610D02*
X35053D01*
G01X35033Y53810D02*
X35503D01*
G01X35483Y54010D02*
X35023D01*
G01X35003Y54200D02*
X35473D01*
G01X35453Y54400D02*
X34983D01*
G01X34973Y54510D02*
X35483D01*
G01X35983Y54810D02*
X34953D01*
G01X34933Y55010D02*
X35803D01*
G01X34873Y55320D02*
X34853Y55350D01*
G01X34913Y55220D02*
X34873Y55320D01*
G01X34913Y55210D02*
Y55220D01*
G01Y55200D02*
Y55210D01*
G01X35613Y55200D02*
X34913D01*
G01X34813Y55400D02*
X35433D01*
G01X35363Y55510D02*
X34713D01*
G01X34623Y55610D02*
X35353D01*
G01X35343Y55700D02*
X34533D01*
G01X34433Y55810D02*
X35333D01*
G01X35323Y55900D02*
X34343D01*
G01X34153Y56110D02*
X35303D01*
G01X35293Y56310D02*
X34813D01*
G01X34603Y57760D02*
X34003D01*
G01X34703Y57670D02*
X34603Y57760D01*
G01X34823Y56320D02*
X34703Y57670D01*
G01X34663Y57700D02*
X35223D01*
G01X35173Y57610D02*
X34713D01*
G01X34723Y57510D02*
X35193D01*
G01Y57400D02*
X34723D01*
G01X34733Y57310D02*
X35203D01*
G01X35213Y57200D02*
X34743D01*
G01X34753Y57110D02*
X35223D01*
G01X35233Y57010D02*
X34763D01*
G01X34773Y56900D02*
X35243D01*
G01Y56810D02*
X34783D01*
G01Y56700D02*
X35253D01*
G01X35263Y56610D02*
X34803D01*
G01Y56510D02*
X35273D01*
G01X35283Y56400D02*
X34813D01*
G01X34653Y56250D02*
X29633Y61640D01*
G01X34763Y56220D02*
X34653Y56250D01*
G01X34823Y56320D02*
X34763Y56220D01*
G01X33973Y56310D02*
X34593D01*
G01X34913Y55200D02*
X35353Y50050D01*
G01X35363Y50010D02*
X35833D01*
G01X35843Y49810D02*
X35373D01*
G01X35393Y49610D02*
X35863D01*
G01X35883Y49400D02*
X35413D01*
G01X35433Y49200D02*
X35903D01*
G01X35943Y49110D02*
X35443D01*
G01X35453Y48460D02*
X35353Y48350D01*
G01X35483Y48530D02*
X35453Y48460D01*
G01X35303Y48310D02*
X35993D01*
G01Y48110D02*
X35113D01*
G01X34923Y47900D02*
X36013D01*
G01X35373Y47700D02*
X34723D01*
G01X34633Y47610D02*
X35283D01*
G01X35183Y47510D02*
X34533D01*
G01X34433Y47400D02*
X35093D01*
G01X34993Y47310D02*
X34343D01*
G01X34153Y47110D02*
X34803D01*
G01X34603Y46900D02*
X33953D01*
G01X35333Y50310D02*
X35803D01*
G01X35783Y50510D02*
X35323D01*
G01X35303Y50700D02*
X35773D01*
G01X35753Y50900D02*
X35283D01*
G01X35263Y51110D02*
X35733D01*
G01X35723Y51310D02*
X35253D01*
G01X35243Y51400D02*
X35713D01*
G01X35703Y51510D02*
X35233D01*
G01X35213Y51700D02*
X35683D01*
G01X35673Y51900D02*
X35203D01*
G01X35183Y52110D02*
X35653D01*
G01X35633Y52310D02*
X35163D01*
G01X35153Y52510D02*
X35613D01*
G01X35593Y52700D02*
X35133D01*
G01X35113Y52900D02*
X35583D01*
G01X35563Y53110D02*
X35093D01*
G01X35083Y53310D02*
X35543D01*
G01X35533Y53510D02*
X35063D01*
G01X35043Y53700D02*
X35513D01*
G01X35493Y53900D02*
X35023D01*
G01X35013Y54110D02*
X35473D01*
G01X35463Y54310D02*
X34993D01*
G01X35623Y54530D02*
X38353Y51590D01*
G01X35503Y54550D02*
X35623Y54530D01*
G01X35453Y54450D02*
X35503Y54550D01*
G01X35723Y51200D02*
X35263D01*
G01X35273Y51010D02*
X35743D01*
G01X35763Y50810D02*
X35293D01*
G01X35313Y50610D02*
X35783D01*
G01X35793Y50400D02*
X35323D01*
G01X35343Y50200D02*
X35813D01*
G01X35823Y50110D02*
X35353D01*
G01X35483Y48590D02*
Y48530D01*
G01X35353Y50050D02*
X35483Y48590D01*
G01X35473Y48510D02*
X36153D01*
G01X36003Y48330D02*
X35983Y48260D01*
G01X36053Y48410D02*
X36003Y48330D01*
G01X35983Y48200D02*
X35213D01*
G01X35023Y48010D02*
X36003D01*
G01X36023Y47700D02*
X35523D01*
G01X35493Y47740D02*
X35393Y47720D01*
G01X35763Y45300D02*
X35873D01*
G01X35763Y45310D02*
Y45300D01*
G01X35563Y47660D02*
X35763Y45310D01*
G01X35493Y47740D02*
X35563Y47660D01*
G01X35863Y45400D02*
X35753D01*
G01X35758D02*
X41353D01*
G01X41418Y45310D02*
X35763D01*
G01X36003Y44260D02*
X36893D01*
G01X35963Y44300D02*
X36003Y44260D01*
G01X35963Y44980D02*
Y44300D01*
G01X35933Y45050D02*
X35963Y44980D01*
G01X35783Y45210D02*
X35933Y45050D01*
G01X35773Y45230D02*
X35783Y45210D01*
G01X35763Y45290D02*
X35773Y45230D01*
G01X36933Y44310D02*
X35963D01*
G01Y44510D02*
X36933D01*
G01Y44700D02*
X35963D01*
G01Y44900D02*
X36933D01*
G01X36213Y45610D02*
X35743D01*
G01X35723Y45700D02*
X36193D01*
G01X36183Y45900D02*
X35713D01*
G01X35693Y46110D02*
X36163D01*
G01X36143Y46310D02*
X35673D01*
G01X35663Y46510D02*
X36133D01*
G01X36113Y46700D02*
X35643D01*
G01X35623Y46900D02*
X36093D01*
G01X36083Y47110D02*
X35613D01*
G01X35593Y47310D02*
X36063D01*
G01X36043Y47510D02*
X35583D01*
G01X35473Y48700D02*
X36343D01*
G01X36533Y48900D02*
X35453D01*
G01X35423Y49310D02*
X35893D01*
G01X35903Y49160D02*
X35453Y54450D01*
G01X35643Y54510D02*
X36263D01*
G01X36453Y54310D02*
X35833D01*
G01X36013Y54110D02*
X36633D01*
G01X35893Y54900D02*
X34943D01*
G01X34923Y55110D02*
X35713D01*
G01X35523Y55310D02*
X34883D01*
G01X35583Y58720D02*
X35473Y58710D01*
G01X35633Y58630D02*
X35583Y58720D01*
G01X35633Y58400D02*
Y58630D01*
G01X35533Y58300D02*
X35633Y58400D01*
G01X35263Y58300D02*
X35533D01*
G01X35463Y58700D02*
X34773D01*
G01X35643Y59690D02*
X35673Y59710D01*
G01X35633Y59660D02*
X35643Y59690D01*
G01X35633Y59460D02*
Y59660D01*
G01X35623Y59420D02*
X35633Y59460D01*
G01X35603Y59370D02*
X35623Y59420D01*
G01X35553Y59310D02*
X35603Y59370D01*
G01X35463Y59270D02*
X35553Y59310D01*
G01X35193Y59110D02*
X35463Y59270D01*
G01X35673Y59700D02*
X36503D01*
G01X35633Y59510D02*
X38523D01*
G01X38513Y59310D02*
X35533D01*
G01X35583Y58700D02*
X36553D01*
G01Y58510D02*
X35633D01*
G01X35543Y58310D02*
X36653D01*
G01X35843Y49900D02*
X35373D01*
G01X35383Y49700D02*
X35853D01*
G01X35873Y49510D02*
X35403D01*
G01X35973Y49070D02*
X36073Y49100D01*
G01X35903Y49160D02*
X35973Y49070D01*
G01X35883Y45110D02*
X41663D01*
G01X36203Y45680D02*
X35983Y48260D01*
G01X36203Y45610D02*
Y45680D01*
G01X36303Y45520D02*
X36203Y45610D01*
G01X40403Y45520D02*
X36303D01*
G01X36053Y48400D02*
X35403D01*
G01X35483Y48610D02*
X36243D01*
G01X36063Y48410D02*
X36053D01*
G01X36063Y48420D02*
Y48410D01*
G01Y48420D02*
X38653Y51110D01*
G01X38463Y50900D02*
X37823D01*
G01X37623Y50700D02*
X38273D01*
G01X38083Y50510D02*
X37433D01*
G01X37243Y50310D02*
X37883D01*
G01X37793Y50200D02*
X37143D01*
G01X37193Y50260D02*
X36073Y49100D01*
G01X36083Y49110D02*
X36723D01*
G01X36633Y49010D02*
X35453D01*
G01X35463Y48810D02*
X36443D01*
G01X36183Y49200D02*
X36823D01*
G01X36923Y49310D02*
X36283D01*
G01X36373Y49400D02*
X37023D01*
G01X37113Y49510D02*
X36473D01*
G01X36563Y49610D02*
X37213D01*
G01X37303Y49700D02*
X36663D01*
G01X36763Y49810D02*
X37403D01*
G01X37503Y49900D02*
X36853D01*
G01X36953Y50010D02*
X37593D01*
G01X37693Y50110D02*
X37043D01*
G01X37873Y52110D02*
X38503D01*
G01X38313Y52310D02*
X37693D01*
G01X37503Y52510D02*
X38123D01*
G01X37943Y52700D02*
X37313D01*
G01X37223Y52810D02*
X37843D01*
G01X37753Y52900D02*
X37133D01*
G01X37043Y53010D02*
X37663D01*
G01X37563Y53110D02*
X36943D01*
G01X36853Y53200D02*
X37473D01*
G01X37383Y53310D02*
X36763D01*
G01X36663Y53400D02*
X37293D01*
G01X37193Y53510D02*
X36573D01*
G01X36483Y53610D02*
X37103D01*
G01X37013Y53700D02*
X36383D01*
G01X36293Y53810D02*
X36913D01*
G01X36823Y53900D02*
X36203D01*
G01X36113Y54010D02*
X36733D01*
G01X36543Y54200D02*
X35923D01*
G01X35733Y54400D02*
X36353D01*
G01X36173Y54610D02*
X34973D01*
G01X34963Y54700D02*
X36083D01*
G01X37933Y53980D02*
X37973Y53940D01*
G01X36553Y58400D02*
X35633D01*
G01X36653Y58300D02*
X36553Y58400D01*
G01X35633Y58610D02*
X36553D01*
G01X37883Y59310D02*
X37993Y59200D01*
G01X37613Y59280D02*
X37883Y59310D01*
G01X37333Y59250D02*
X37613Y59280D01*
G01X37213Y59240D02*
X37333Y59250D01*
G01X37113Y59220D02*
X37213Y59240D01*
G01X36863Y59180D02*
X37113Y59220D01*
G01X36853Y59180D02*
X36863D01*
G01X36763Y59160D02*
X36853Y59180D01*
G01X36753Y59160D02*
X36763D01*
G01X36633Y59140D02*
X36753Y59160D01*
G01X36553Y59040D02*
X36633Y59140D01*
G01X36553Y58400D02*
Y59040D01*
G01X36493Y59710D02*
X35673D01*
G01X36513Y59700D02*
X36493Y59710D01*
G01X36543Y59690D02*
X36513Y59700D01*
G01X36573Y59670D02*
X36543Y59690D01*
G01X36653Y59650D02*
X36573Y59670D01*
G01X36673Y59660D02*
X36653Y59650D01*
G01X36913Y59700D02*
X36673Y59660D01*
G01X37413Y59770D02*
X36913Y59700D01*
G01X37533Y59780D02*
X37413Y59770D01*
G01X37593Y59780D02*
X37533D01*
G01X37753Y59800D02*
X37593Y59780D01*
G01X37893Y59810D02*
X37753Y59800D01*
G01X35353Y59200D02*
X37003D01*
G01X36553Y58900D02*
X34983D01*
G01X36653Y58300D02*
X42493D01*
G01X40563Y59810D02*
X37873D01*
G01X37893D02*
X37993Y59910D01*
G01X36023Y47810D02*
X34823D01*
G01X35563Y47610D02*
X36033D01*
G01X36053Y47400D02*
X35583D01*
G01X35603Y47200D02*
X36073D01*
G01X36083Y47010D02*
X35613D01*
G01X35633Y46810D02*
X36103D01*
G01X36123Y46610D02*
X35653D01*
G01X35673Y46400D02*
X36133D01*
G01X36153Y46200D02*
X35693D01*
G01X35703Y46010D02*
X36173D01*
G01X36193Y45810D02*
X35723D01*
G01X35953Y45010D02*
X37003D01*
G01X36933Y44300D02*
X36893Y44260D01*
G01X36933Y44940D02*
Y44300D01*
G01X37033Y45040D02*
X36933Y44940D01*
G01Y44400D02*
X35963D01*
G01Y44610D02*
X36933D01*
G01Y44810D02*
X35963D01*
G01X40503Y45990D02*
Y46000D01*
G01X40493Y45920D02*
X40503Y45990D01*
G01X40493Y45660D02*
Y45920D01*
G01X40503Y45640D02*
X40493Y45660D01*
G01X40403Y45520D02*
X40503Y45640D01*
G01Y46010D02*
X41273D01*
G01X41233Y45810D02*
X40493D01*
G01X40473Y45610D02*
X41273D01*
G01X39113Y51440D02*
Y51580D01*
G01X41813Y48540D02*
X39113Y51440D01*
G01X39133Y51610D02*
X38343D01*
G01X38353Y51450D02*
X37193Y50260D01*
G01X38353Y51590D02*
Y51450D01*
G01X37343Y50400D02*
X37983D01*
G01X38173Y50610D02*
X37533D01*
G01X37723Y50810D02*
X38373D01*
G01X38563Y51010D02*
X37913D01*
G01X38803Y51110D02*
X40483Y49290D01*
G01X38653Y51110D02*
X38803D01*
G01X38013D02*
X38653D01*
G01X40473Y49310D02*
X41103D01*
G01X40913Y49510D02*
X40283D01*
G01X40103Y49700D02*
X40733D01*
G01X40543Y49900D02*
X39913D01*
G01X39823Y50010D02*
X40453D01*
G01X40353Y50110D02*
X39723D01*
G01X39633Y50200D02*
X40263D01*
G01X40173Y50310D02*
X39543D01*
G01X39453Y50400D02*
X40083D01*
G01X39983Y50510D02*
X39353D01*
G01X39263Y50610D02*
X39893D01*
G01X39803Y50700D02*
X39173D01*
G01X39083Y50810D02*
X39713D01*
G01X39613Y50900D02*
X38983D01*
G01X38893Y51010D02*
X39523D01*
G01X39433Y51110D02*
X38783D01*
G01X39153Y51400D02*
X38303D01*
G01X38353Y51510D02*
X39113D01*
G01X39233Y51700D02*
X38243D01*
G01X38153Y51810D02*
X39333D01*
G01X39433Y51900D02*
X38063D01*
G01X37973Y52010D02*
X38593D01*
G01X38803Y51930D02*
X40233Y53400D01*
G01X38663Y51930D02*
X38803D01*
G01X40133Y53310D02*
X40773D01*
G01X40583Y53110D02*
X39943D01*
G01X39853Y53010D02*
X40483D01*
G01X40393Y52900D02*
X39753D01*
G01X39653Y52810D02*
X40293D01*
G01X40203Y52700D02*
X39563D01*
G01X39463Y52610D02*
X40103D01*
G01X40003Y52510D02*
X39363D01*
G01X39273Y52400D02*
X39913D01*
G01X39813Y52310D02*
X39173D01*
G01X39083Y52200D02*
X39713D01*
G01X39623Y52110D02*
X38983D01*
G01X38883Y52010D02*
X39523D01*
G01X39243Y51310D02*
X38213D01*
G01X38113Y51200D02*
X39333D01*
G01X38403Y52200D02*
X37783D01*
G01X37593Y52400D02*
X38223D01*
G01X38033Y52610D02*
X37413D01*
G01X38023Y53940D02*
X40513D01*
G01X37973D02*
X38023D01*
G01X40523Y53700D02*
X41163D01*
G01X40973Y53510D02*
X40333D01*
G01X41453Y54010D02*
X37933D01*
G01X37973Y54970D02*
X38023D01*
G01X37933Y54930D02*
X37973Y54970D01*
G01X37933Y53980D02*
Y54930D01*
G01Y54810D02*
X41193D01*
G01X41223Y54610D02*
X37933D01*
G01Y54400D02*
X41843D01*
G01X41643Y54200D02*
X37933D01*
G01X37993Y58860D02*
Y59200D01*
G01X38033Y58810D02*
X37993Y58860D01*
G01X37983Y59200D02*
X40613D01*
G01X40483Y58810D02*
X38033D01*
G01X40533Y58860D02*
X40483Y58810D01*
G01X40533Y59140D02*
Y58860D01*
G01X37993Y58900D02*
X40533D01*
G01Y59010D02*
X37993D01*
G01Y59110D02*
X40533D01*
G01X40083Y59420D02*
Y59380D01*
G01X39983Y59520D02*
X40083Y59420D01*
G01X38543Y59520D02*
X39983D01*
G01X38443Y59420D02*
X38543Y59520D01*
G01X38443Y59380D02*
Y59420D01*
G01X38543Y59270D02*
X38443Y59380D01*
G01X39983Y59270D02*
X38543D01*
G01X40083Y59380D02*
X39983Y59270D01*
G01X40083Y59400D02*
X42053D01*
G01X41763Y59510D02*
X39993D01*
G01X37993Y59940D02*
Y59910D01*
G01X38033Y59980D02*
X37993Y59940D01*
G01X40483Y59980D02*
X38033D01*
G01X40533Y59940D02*
X40483Y59980D01*
G01X40533Y59840D02*
Y59940D01*
G01X37983Y59900D02*
X40533D01*
G01X38443Y59400D02*
X35613D01*
G01X35633Y59610D02*
X41393D01*
G01X40613Y59740D02*
X40533Y59840D01*
G01X40663Y59740D02*
X40613D01*
G01X41223Y59650D02*
X40663Y59740D01*
G01X41403Y59610D02*
X41223Y59650D01*
G01X40843Y59700D02*
X36973D01*
G01X41043Y59170D02*
X41453Y59080D01*
G01X40753Y59220D02*
X41043Y59170D01*
G01X40723Y59220D02*
X40753D01*
G01X40643Y59240D02*
X40723Y59220D01*
G01X40533Y59140D02*
X40643Y59240D01*
G01X40833Y59200D02*
X42423D01*
G01X41143Y54970D02*
X38023D01*
G01X37933Y54900D02*
X41193D01*
G01X41183Y54930D02*
X41143Y54970D01*
G01X41363Y54580D02*
X41563Y54780D01*
G01X41253Y54550D02*
X41363Y54580D01*
G01X41193Y54650D02*
X41253Y54550D01*
G01X41193Y54830D02*
Y54650D01*
G01Y54840D02*
Y54830D01*
G01X41183Y54930D02*
X41193Y54840D01*
G01X41393Y54610D02*
X42033D01*
G01X41193Y54700D02*
X37933D01*
G01X40043Y53200D02*
X40683D01*
G01X40603Y53880D02*
X40513Y53940D01*
G01X40583Y53770D02*
X40603Y53880D01*
G01X40233Y53400D02*
X40583Y53770D01*
G01X40873Y53400D02*
X40233D01*
G01X40563Y53900D02*
X41353D01*
G01X41263Y53810D02*
X40593D01*
G01X40433Y53610D02*
X41063D01*
G01X40633Y49810D02*
X40003D01*
G01X40193Y49610D02*
X40823D01*
G01X41003Y49400D02*
X40373D01*
G01X40563Y49200D02*
X41193D01*
G01X41283Y49110D02*
X40653D01*
G01X40743Y49010D02*
X41383D01*
G01X41473Y48900D02*
X40843D01*
G01X40933Y48810D02*
X41563D01*
G01X41753Y48610D02*
X41123D01*
G01X41303Y48400D02*
X42443D01*
G01X42433Y48310D02*
X41403D01*
G01X40543Y46180D02*
X40503Y46000D01*
G01X40543Y46190D02*
Y46180D01*
G01X40653Y46500D02*
X40543Y46190D01*
G01X40663Y46510D02*
X40653Y46500D01*
G01X40873Y46820D02*
X40663Y46510D01*
G01X40883Y46830D02*
X40873Y46820D01*
G01X41123Y47050D02*
X40883Y46830D01*
G01X41133Y47050D02*
X41123D01*
G01X41253Y47130D02*
X41133Y47050D01*
G01X41263Y47140D02*
X41253Y47130D01*
G01X41323Y47170D02*
X41263Y47140D01*
G01X41483Y47240D02*
X41323Y47170D01*
G01X40493Y45900D02*
X41253D01*
G01X41293Y45510D02*
X35743D01*
G01X41283Y45530D02*
X41293Y45510D01*
G01X41233Y45790D02*
X41283Y45530D01*
G01X41233Y45800D02*
Y45790D01*
G01Y45820D02*
Y45800D01*
G01X35783Y45200D02*
X41523D01*
G01X41443Y45270D02*
X41383Y45360D01*
G01X41453Y45260D02*
X41443Y45270D01*
G01X41463Y45250D02*
X41453Y45260D01*
G01X41303Y45500D02*
X41293Y45510D01*
G01X41383Y45370D02*
X41303Y45500D01*
G01X41253Y45700D02*
X40493D01*
G01X40523Y46110D02*
X41293D01*
G01X41283Y46080D02*
X41233Y45820D01*
G01X41293Y46100D02*
X41283Y46080D01*
G01X41513Y45830D02*
X41523Y45850D01*
G01X41463Y46360D02*
X41683Y46520D01*
G01X41453Y46350D02*
X41463Y46360D01*
G01X41443Y46330D02*
X41453Y46350D01*
G01X41303Y46120D02*
X41443Y46330D01*
G01X41293Y46100D02*
X41303Y46120D01*
G01X41523Y46400D02*
X40623D01*
G01X40583Y46310D02*
X41423D01*
G01X41353Y46200D02*
X40543D01*
G01X40723Y46610D02*
X41983D01*
G01X41393Y47200D02*
X43063D01*
G01X43153Y47110D02*
X41213D01*
G01X40973Y46900D02*
X43343D01*
G01X43523Y46700D02*
X40803D01*
G01X41383Y45310D02*
X41423D01*
G01X41463Y45250D02*
X41683Y45090D01*
G01X41253Y44510D02*
X42803D01*
G01X42963Y44610D02*
X41073D01*
G01X40633Y45040D02*
X37033D01*
G01X40713Y45010D02*
X40633Y45040D01*
G01X40723Y45000D02*
X40713Y45010D01*
G01X40723Y44990D02*
Y45000D01*
G01X40763Y44920D02*
X40723Y44990D01*
G01X40773Y44920D02*
X40763D01*
G01X40783Y44910D02*
X40773Y44920D01*
G01X40853Y44810D02*
X40783Y44910D01*
G01X40863Y44800D02*
X40853Y44810D01*
G01X41093Y44580D02*
X40863Y44800D01*
G01Y44810D02*
X43203D01*
G01X41113Y44570D02*
X41093Y44580D01*
G01X41913Y44270D02*
X42253Y44280D01*
G01X41903Y44270D02*
X41913D01*
G01X41893D02*
X41903D01*
G01X41733Y44290D02*
X41893Y44270D01*
G01X41713Y44290D02*
X41733D01*
G01X41113Y44570D02*
X41713Y44290D01*
G01X42363Y44310D02*
X41693D01*
G01Y45080D02*
X41683Y45090D01*
G01X41713Y45080D02*
X41693D01*
G01X41883Y45020D02*
X41713Y45080D01*
G01X42103Y45010D02*
X42123D01*
G01X41973D02*
X42103D01*
G01X41903Y45020D02*
X41973Y45010D01*
G01X41883Y45020D02*
X41903D01*
G01X41543Y45640D02*
X41513Y45830D01*
G01X41553Y45610D02*
X41543Y45640D01*
G01X41723Y45390D02*
X41553Y45610D01*
G01X41743Y45380D02*
X41723Y45390D01*
G01X41913Y45300D02*
X41743Y45380D01*
G01X41923Y45300D02*
X41913D01*
G01X41963Y45290D02*
X41923Y45300D01*
G01X42023Y45290D02*
X41963D01*
G01X42043D02*
X42023D01*
G01X42073Y46320D02*
X42083D01*
G01X41983D02*
X42073D01*
G01X41963Y46310D02*
X41983Y46320D01*
G01X41653Y46150D02*
X41963Y46310D01*
G01X41633Y46130D02*
X41653Y46150D01*
G01X41523Y45850D02*
X41633Y46130D01*
G01X41693Y46530D02*
X41683Y46520D01*
G01X41713Y46530D02*
X41693D01*
G01X41883Y46590D02*
X41713Y46530D01*
G01X41903Y46590D02*
X41883D01*
G01X41973Y46600D02*
X41903Y46590D01*
G01X41993Y46610D02*
X41973Y46600D01*
G01X42053Y46610D02*
X41993D01*
G01X42083Y46600D02*
X42053Y46610D01*
G01X41663Y46510D02*
X40663D01*
G01X41573Y45990D02*
X42513D01*
G01X42533Y45790D02*
X41523D01*
G01X41573Y45590D02*
X42483D01*
G01X42303Y45390D02*
X41733D01*
G01X42043Y45290D02*
X42173Y45310D01*
G01X42373Y46180D02*
X41723D01*
G01X42123Y46600D02*
X42323Y46550D01*
G01X42083Y46600D02*
X42123D01*
G01X41573Y47270D02*
X41483Y47240D01*
G01X41583Y47280D02*
X41573Y47270D01*
G01X41723Y47310D02*
X41583Y47280D01*
G01X41803Y47330D02*
X41723Y47310D01*
G01X41583Y48110D02*
X40483Y49290D01*
G01X41843Y47830D02*
X41583Y48110D01*
G01X41873Y47780D02*
X41843Y47830D01*
G01X41903Y47630D02*
X41873Y47780D01*
G01X41913Y47610D02*
X41903Y47630D01*
G01X41913Y47590D02*
Y47610D01*
G01X41893Y47420D02*
X41913Y47590D01*
G01X41893Y47410D02*
Y47420D01*
G01X41803Y47330D02*
X41893Y47410D01*
G01X41023Y48700D02*
X41663D01*
G01X41983Y48600D02*
X42493Y54830D01*
G01X41923Y48520D02*
X41983Y48600D01*
G01X41813Y48540D02*
X41923Y48520D01*
G01X41583Y54810D02*
X41563Y54780D01*
G01X42223Y54810D02*
X41583D01*
G01D02*
X42393Y55650D01*
G01X41973Y55200D02*
X44233D01*
G01Y55010D02*
X41783D01*
G01X41483Y54700D02*
X42123D01*
G01X41933Y54510D02*
X37933D01*
G01Y54310D02*
X41743D01*
G01X41543Y54110D02*
X37933D01*
G01X42153Y50610D02*
X42613D01*
G01X42603Y50400D02*
X42133D01*
G01X42113Y50200D02*
X42583D01*
G01X42573Y50010D02*
X42103D01*
G01X42083Y49810D02*
X42553D01*
G01X42543Y49610D02*
X42073D01*
G01X42053Y49400D02*
X42523D01*
G01X42503Y49200D02*
X42043D01*
G01X42023Y49010D02*
X42483D01*
G01X42473Y48810D02*
X42003D01*
G01X41983Y48610D02*
X42453D01*
G01X42413Y48110D02*
X41583D01*
G01X41773Y47900D02*
X42413D01*
G01X42593Y47700D02*
X41893D01*
G01X41903Y47510D02*
X42783D01*
G01X41733Y59000D02*
X41453Y59080D01*
G01X41743Y58990D02*
X41733Y59000D01*
G01X41853Y58960D02*
X41743Y58990D01*
G01X41853Y58950D02*
Y58960D01*
G01X41963Y58910D02*
X41853Y58950D01*
G01X41973Y58900D02*
X41963Y58910D01*
G01X42833Y58900D02*
X41973D01*
G01X41693Y59010D02*
X42723D01*
G01X41523Y59570D02*
X41403Y59610D01*
G01X41633Y59550D02*
X41523Y59570D01*
G01X41873Y59470D02*
X41633Y59550D01*
G01X41983Y59430D02*
X41873Y59470D01*
G01X42043Y59410D02*
X41983Y59430D01*
G01X41333Y59110D02*
X42583D01*
G01X42263Y59310D02*
X40013D01*
G01X42583Y58350D02*
X42493Y58300D01*
G01X42573Y58450D02*
X42583Y58350D01*
G01X42503Y58560D02*
X42573Y58450D01*
G01X42483Y58580D02*
X42503Y58560D01*
G01X42183Y58800D02*
X42483Y58580D01*
G01X42173Y58810D02*
X42183Y58800D01*
G01X42163Y58810D02*
X42173D01*
G01X41973Y58900D02*
X42163Y58810D01*
G01X42503Y58310D02*
X44223D01*
G01X44203Y58510D02*
X42543D01*
G01X42313Y58700D02*
X44123D01*
G01X44233Y56700D02*
X42453D01*
G01X42423Y55680D02*
X42393Y55650D01*
G01X42453Y55740D02*
X42423Y55680D01*
G01X42453Y56760D02*
Y55740D01*
G01X42353Y55610D02*
X43023D01*
G01X43193Y55810D02*
X42453D01*
G01Y56010D02*
X43383D01*
G01X43573Y56200D02*
X42453D01*
G01Y56310D02*
X44233D01*
G01Y56510D02*
X42453D01*
G01X42563Y56840D02*
X42663Y56940D01*
G01X42493Y56840D02*
X42563D01*
G01X42453Y56800D02*
X42493Y56840D01*
G01X42453Y56760D02*
Y56800D01*
G01X42163Y55400D02*
X44233D01*
G01X42953Y54700D02*
X42483D01*
G01X42323Y54910D02*
X39113Y51580D01*
G01X42433Y54930D02*
X42323Y54910D01*
G01X42493Y54830D02*
X42433Y54930D01*
G01X42213Y51400D02*
X42683D01*
G01X42693Y51510D02*
X42223D01*
G01X42243Y51700D02*
X42713D01*
G01X42723Y51900D02*
X42263D01*
G01X42273Y52110D02*
X42743D01*
G01X42753Y52310D02*
X42293D01*
G01X42303Y52510D02*
X42773D01*
G01X42793Y52700D02*
X42323D01*
G01X42343Y52900D02*
X42803D01*
G01X42823Y53110D02*
X42353D01*
G01X42373Y53310D02*
X42843D01*
G01X42853Y53510D02*
X42393D01*
G01X42403Y53700D02*
X42873D01*
G01X42883Y53900D02*
X42423D01*
G01X42433Y54110D02*
X42903D01*
G01X42923Y54310D02*
X42453D01*
G01X42473Y54510D02*
X42933D01*
G01X42323Y54900D02*
X41683D01*
G01X42203Y51200D02*
X42673D01*
G01X42653Y51010D02*
X42183D01*
G01X42173Y50810D02*
X42633D01*
G01X42623Y50700D02*
X42163D01*
G01X42143Y50510D02*
X42613D01*
G01X42593Y50310D02*
X42123D01*
G01X42113Y50110D02*
X42583D01*
G01X42563Y49900D02*
X42093D01*
G01X42083Y49700D02*
X42543D01*
G01X42533Y49510D02*
X42063D01*
G01X42043Y49310D02*
X42513D01*
G01X42493Y49110D02*
X42033D01*
G01X42013Y48900D02*
X42483D01*
G01X42463Y48700D02*
X41993D01*
G01X42453Y48510D02*
X41213D01*
G01X41493Y48200D02*
X42423D01*
G01X42413Y48010D02*
X41683D01*
G01X41853Y47810D02*
X42493D01*
G01X42433Y47870D02*
X43393Y46850D01*
G01X43713Y46510D02*
X42383D01*
G01X42363Y46530D02*
X42323Y46550D01*
G01X42363Y46530D02*
X42673Y46270D01*
G01X42443Y46090D02*
X41613D01*
G01X41533Y45890D02*
X42523D01*
G01X42333Y46220D02*
X42083Y46320D01*
G01X42353Y46210D02*
X42333Y46220D01*
G01X42503Y46010D02*
X42353Y46210D01*
G01X42513Y45980D02*
X42503Y46010D01*
G01X42173Y46290D02*
X41903D01*
G01X42193Y45310D02*
X42173D01*
G01X42413Y45450D02*
X42193Y45310D01*
G01X42423Y45470D02*
X42413Y45450D01*
G01X42533Y45700D02*
X42423Y45470D01*
G01X42543Y45720D02*
X42533Y45700D01*
G01X42513Y45980D02*
X42543Y45720D01*
G01X42383Y45110D02*
X43403D01*
G01X42263Y44280D02*
X42253D01*
G01X42553Y44350D02*
X42263Y44280D01*
G01X42563Y44360D02*
X42553Y44350D01*
G01X43073Y44670D02*
X42563Y44360D01*
G01X42323Y45060D02*
X42363Y45080D01*
G01X42123Y45010D02*
X42323Y45060D01*
G01X42433Y45490D02*
X41653D01*
G01X41533Y45680D02*
X42533D01*
G01X42423Y47890D02*
X42403Y47960D01*
G01X42433Y47880D02*
X42423Y47890D01*
G01X42433Y47870D02*
Y47880D01*
G01X42193Y59350D02*
X42043Y59410D01*
G01X42203Y59340D02*
X42193Y59350D01*
G01X43453Y59060D02*
X43513Y59070D01*
G01X43443Y59060D02*
X43453D01*
G01X43333Y59030D02*
X43443Y59060D01*
G01X43323Y59030D02*
X43333D01*
G01X43193Y58980D02*
X43323Y59030D01*
G01X43193Y58970D02*
Y58980D01*
G01X43133Y58940D02*
X43193Y58970D01*
G01X43113Y58920D02*
X43133Y58940D01*
G01X43053Y58870D02*
X43113Y58920D01*
G01X43033Y58850D02*
X43053Y58870D01*
G01X42893Y58850D02*
X43033D01*
G01X42713Y59020D02*
X42893Y58850D01*
G01X42703Y59030D02*
X42713Y59020D01*
G01X42203Y59340D02*
X42703Y59030D01*
G01X43263Y59010D02*
X43783D01*
G01X43833Y57700D02*
X42673D01*
G01X42723Y57650D02*
X42663Y56940D01*
G01X42633Y56900D02*
X43183D01*
G01X43473Y57630D02*
X43503Y57620D01*
G01X43393Y57640D02*
X43473Y57630D01*
G01X43323Y57660D02*
X43393Y57640D01*
G01X43313Y57660D02*
X43323D01*
G01X43183Y57570D02*
X43313Y57660D01*
G01X43133Y56960D02*
X43183Y57570D01*
G01X43233Y56850D02*
X43133Y56960D01*
G01X43233Y57610D02*
X42723D01*
G01X42623Y57760D02*
X35273D01*
G01X42723Y57650D02*
X42623Y57760D01*
G01X42263Y55510D02*
X43083D01*
G01X43053Y55660D02*
X43603Y56240D01*
G01X43023Y55610D02*
X43053Y55660D01*
G01X43023Y55570D02*
Y55610D01*
G01X43123Y55460D02*
X43023Y55570D01*
G01X43483Y56110D02*
X42453D01*
G01Y55900D02*
X43283D01*
G01X43093Y55700D02*
X42433D01*
G01X42453Y54900D02*
X42983D01*
G01X42973Y54890D02*
X42403Y47960D01*
G01X42683Y47610D02*
X41913D01*
G01X41883Y47400D02*
X42873D01*
G01X42963Y47310D02*
X41693D01*
G01X41083Y47010D02*
X43243D01*
G01X43433Y46810D02*
X40863D01*
G01X40713Y45010D02*
X43343D01*
G01X43163Y44760D02*
X43073Y44670D01*
G01X43223Y44830D02*
X43163Y44760D01*
G01X43353Y45020D02*
X43223Y44830D01*
G01X43113Y44700D02*
X40963D01*
G01X40783Y44900D02*
X43273D01*
G01X43473Y45270D02*
X43533Y45440D01*
G01X43433Y45170D02*
X43473Y45270D01*
G01X43433Y45160D02*
Y45170D01*
G01X43363Y45030D02*
X43433Y45160D01*
G01X43353Y45020D02*
X43363Y45030D01*
G01X43523Y45400D02*
X42708D01*
G01X42713D02*
X42773D01*
G01X42673Y45340D02*
X42363Y45080D01*
G01X42703Y45390D02*
X42673Y45340D01*
G01X42503Y45200D02*
X43453D01*
G01X43483Y45310D02*
X42693D01*
G01X43453D02*
X43483D01*
G01X42703Y46220D02*
X42673Y46270D01*
G01X42823Y45830D02*
X42703Y46220D01*
G01X42823Y45770D02*
Y45830D01*
G01X42703Y45390D02*
X42823Y45770D01*
G01X42633Y46310D02*
X43893D01*
G01X44083Y46110D02*
X42743D01*
G01X42803Y45900D02*
X44263D01*
G01X43563Y45700D02*
X42803D01*
G01X42743Y45510D02*
X43543D01*
G01X42633Y44400D02*
X41473D01*
G01X42173Y50900D02*
X42643D01*
G01X42663Y51110D02*
X42193D01*
G01X42213Y51310D02*
X42673D01*
G01X42703Y51610D02*
X42233D01*
G01X42243Y51810D02*
X42713D01*
G01X42733Y52010D02*
X42263D01*
G01X42283Y52200D02*
X42743D01*
G01X42763Y52400D02*
X42303D01*
G01X42313Y52610D02*
X42783D01*
G01X42803Y52810D02*
X42333D01*
G01X42343Y53010D02*
X42813D01*
G01X42833Y53200D02*
X42363D01*
G01X42383Y53400D02*
X42843D01*
G01X42863Y53610D02*
X42393D01*
G01X42413Y53810D02*
X42873D01*
G01X42893Y54010D02*
X42433D01*
G01X42443Y54200D02*
X42913D01*
G01X42933Y54400D02*
X42463D01*
G01X42473Y54610D02*
X42943D01*
G01X42963Y54810D02*
X42493D01*
G01X42973Y54890D02*
X43063Y54980D01*
G01X43393Y56840D02*
X43513D01*
G01X43233Y56850D02*
X43393Y56840D01*
G01X43143Y57010D02*
X42673D01*
G01X42683Y57110D02*
X43153D01*
G01Y57200D02*
X42693D01*
G01Y57310D02*
X43163D01*
G01X43173Y57400D02*
X42703D01*
G01X42713Y57510D02*
X43183D01*
G01X43583Y59070D02*
X43513D01*
G01X43593Y59060D02*
X43583Y59070D01*
G01X43853Y58990D02*
X43593Y59060D01*
G01X43863Y58980D02*
X43853Y58990D01*
G01X44063Y58810D02*
X43863Y58980D01*
G01X44073Y58800D02*
X44063Y58810D01*
G01X44193Y58570D02*
X44073Y58800D01*
G01X44203Y58550D02*
X44193Y58570D01*
G01X44223Y58270D02*
X44203Y58550D01*
G01X44223Y58260D02*
Y58270D01*
G01X44143Y58000D02*
X44223Y58260D01*
G01X44133Y57990D02*
X44143Y58000D01*
G01X43973Y57790D02*
X44133Y57990D01*
G01X43963Y57770D02*
X43973Y57790D01*
G01X43733Y57650D02*
X43963Y57770D01*
G01X43713Y57650D02*
X43733D01*
G01X43593Y57630D02*
X43713Y57650D01*
G01X43583Y57630D02*
X43593D01*
G01X43523Y57620D02*
X43583Y57630D01*
G01X43503Y57620D02*
X43523D01*
G01X43093Y58900D02*
X43953D01*
G01X44063Y58810D02*
X42173D01*
G01X42453Y58610D02*
X44173D01*
G01X44213Y58400D02*
X42583D01*
G01X44073Y57900D02*
X33963D01*
G01Y58110D02*
X44173D01*
G01X44483Y57810D02*
X45113D01*
G01X45213Y57900D02*
X44583D01*
G01X44673Y58010D02*
X45313D01*
G01X45403Y58110D02*
X44773D01*
G01X44873Y58200D02*
X45503D01*
G01X45593Y58310D02*
X44973D01*
G01X45063Y58400D02*
X45693D01*
G01X45793Y58510D02*
X45163D01*
G01X45263Y58610D02*
X45893D01*
G01X46083Y58810D02*
X45453D01*
G01X45643Y59010D02*
X46273D01*
G01X45023Y57700D02*
X44393D01*
G01X44293Y57610D02*
X44923D01*
G01X44823Y57510D02*
X44193D01*
G01X44093Y57400D02*
X44733D01*
G01X44633Y57310D02*
X44003D01*
G01X43903Y57200D02*
X44543D01*
G01X44443Y57110D02*
X43813D01*
G01X43713Y57010D02*
X44343D01*
G01X44193Y54980D02*
X43063D01*
G01X44233Y55000D02*
X44193Y54980D01*
G01X44233Y55010D02*
Y55000D01*
G01Y56830D02*
Y55010D01*
G01Y56840D02*
Y56830D01*
G01X44263Y56920D02*
X44233Y56840D01*
G01X43713Y56260D02*
X43603Y56240D01*
G01X43773Y56160D02*
X43713Y56260D01*
G01X43773Y55560D02*
Y56160D01*
G01X43673Y55460D02*
X43773Y55560D01*
G01X43123Y55460D02*
X43673D01*
G01X43743Y56200D02*
X44233D01*
G01Y56110D02*
X43773D01*
G01Y56010D02*
X44233D01*
G01Y55900D02*
X43773D01*
G01Y55810D02*
X44233D01*
G01Y55700D02*
X43773D01*
G01Y55610D02*
X44233D01*
G01Y55510D02*
X43723D01*
G01X44233Y55310D02*
X42063D01*
G01X41873Y55110D02*
X44233D01*
G01Y56400D02*
X42453D01*
G01Y56610D02*
X44233D01*
G01Y56810D02*
X42453D01*
G01X43513Y56840D02*
X43583Y56870D01*
G01X43613Y56900D02*
X44253D01*
G01X43613Y46610D02*
X42063D01*
G01X42503Y46400D02*
X43803D01*
G01X43983Y46200D02*
X42713D01*
G01X42763Y46010D02*
X44173D01*
G01X44363Y45810D02*
X43673D01*
G01X43533Y45460D02*
Y45440D01*
G01X43573Y45730D02*
X43533Y45460D01*
G01X43633Y45810D02*
X43573Y45730D01*
G01X43553Y45610D02*
X42773D01*
G01X43633Y45810D02*
X43743Y45790D01*
G01X42823Y45810D02*
X43633D01*
G01X43823Y45700D02*
X44453D01*
G01X44543Y45610D02*
X43913D01*
G01X44003Y45510D02*
X44643D01*
G01X44693Y45400D02*
X44733D01*
G01X44743D02*
X44103D01*
G01X44193Y45310D02*
X44828D01*
G01X44823D02*
X44773D01*
G01X44928Y45200D02*
X44283D01*
G01X44373Y45110D02*
X45013D01*
G01X45103Y45010D02*
X44468D01*
G01X44568Y44900D02*
X45203D01*
G01X45293Y44810D02*
X44653D01*
G01X44758Y44700D02*
X45383D01*
G01X45483Y44610D02*
X44843D01*
G01X44933Y44510D02*
X45573D01*
G01X45663Y44400D02*
X45023D01*
G01X45113Y44310D02*
X45763D01*
G01X45943Y44110D02*
X45303D01*
G01X45213Y44200D02*
X45853D01*
G01X46033Y44010D02*
X45393D01*
G01X45493Y43900D02*
X46133D01*
G01X46223Y43810D02*
X45583D01*
G01X45673Y43700D02*
X46313D01*
G01X46413Y43610D02*
X45763D01*
G01X45863Y43510D02*
X46503D01*
G01X46593Y43400D02*
X45953D01*
G01X46043Y43310D02*
X46693D01*
G01X46783Y43200D02*
X46143D01*
G01X46233Y43110D02*
X46873D01*
G01X47063Y42900D02*
X46423D01*
G01X46603Y42700D02*
X47213D01*
G01X47203Y42760D02*
X43393Y46850D01*
G01X46873Y42420D02*
X46893Y42400D01*
G01X43743Y45790D02*
X46873Y42420D01*
G01X46793Y42510D02*
X47013D01*
G01X29933Y42740D02*
X35353Y48350D01*
G01X29903Y42710D02*
X29933Y42740D01*
G01X29913Y42690D02*
X29903Y42710D01*
G01X30223Y42420D02*
X29913Y42690D01*
G01X30253Y42410D02*
X30223Y42420D01*
G01X30273D02*
X30253Y42410D01*
G01X35393Y47720D02*
X30273Y42420D01*
G01X30353Y42510D02*
X30123D01*
G01X30003Y42610D02*
X30453D01*
G01X30553Y42700D02*
X29903D01*
G01X29993Y42810D02*
X30653D01*
G01X30743Y42900D02*
X30093D01*
G01X30183Y43010D02*
X30843D01*
G01X30933Y43110D02*
X30283D01*
G01X30373Y43200D02*
X31033D01*
G01X31133Y43310D02*
X30473D01*
G01X30573Y43400D02*
X31223D01*
G01X31323Y43510D02*
X30673D01*
G01X30763Y43610D02*
X31423D01*
G01X31513Y43700D02*
X30863D01*
G01X30963Y43810D02*
X31613D01*
G01X31713Y43900D02*
X31053D01*
G01X31153Y44010D02*
X31803D01*
G01X43583Y56870D02*
X48163Y61610D01*
G01X48193Y61000D02*
X44263Y56920D01*
G01X45353Y58700D02*
X45983D01*
G01X46173Y58900D02*
X45543D01*
G01X45743Y59110D02*
X46373D01*
G01X46473Y59200D02*
X45843D01*
G01X45933Y59310D02*
X46563D01*
G01X46663Y59400D02*
X46033D01*
G01X46133Y59510D02*
X46753D01*
G01X46853Y59610D02*
X46223D01*
G01X46413Y59810D02*
X47043D01*
G01X47243Y60010D02*
X46613D01*
G01X46803Y60200D02*
X47433D01*
G01X47333Y60110D02*
X46713D01*
G01X46903Y60310D02*
X47523D01*
G01X47623Y60400D02*
X46993D01*
G01X47093Y60510D02*
X47723D01*
G01X47823Y60610D02*
X47193D01*
G01X47143Y59900D02*
X46513D01*
G01X46323Y59700D02*
X46953D01*
G01X46973Y43010D02*
X46323D01*
G01X46513Y42810D02*
X47153D01*
G01X46923Y42420D02*
X46893Y42400D01*
G01X47213Y42710D02*
X46923Y42420D01*
G01X47223Y42730D02*
X47213Y42710D01*
G01Y42740D02*
X47223Y42730D01*
G01X47203Y42760D02*
X47213Y42740D01*
G01X46693Y42610D02*
X47113D01*
G01X47283Y60700D02*
X47913D01*
G01X48013Y60810D02*
X47383D01*
G01X47483Y60900D02*
X48103D01*
G01X48213Y61110D02*
X47673D01*
G01X48203Y61030D02*
X48213Y61110D01*
G01X48193Y61000D02*
X48203Y61030D01*
G01X47583Y61010D02*
X48193D01*
G01X48213Y61600D02*
X48163Y61610D01*
G01X48213Y61110D02*
Y61600D01*
G01X48153Y61610D02*
X48193D01*
G01X48213Y61510D02*
X48063D01*
G01X47963Y61400D02*
X48213D01*
G01Y61310D02*
X47863D01*
G01X47773Y61200D02*
X48213D01*
G54D14*
G01X-44374Y-163263D02*
Y-145763D01*
G01X-35204D02*
Y-163263D01*
G01Y-154513D02*
X-44374D01*
G01X-22289Y-163263D02*
X-23599Y-162971D01*
X-24909Y-161805D01*
X-25783Y-159763D01*
X-26219Y-157430D01*
X-25783Y-155096D01*
X-24909Y-153055D01*
X-23599Y-151888D01*
X-22289Y-151597D01*
X-20979Y-151888D01*
X-19669Y-153055D01*
X-18796Y-155096D01*
X-18577Y-157430D01*
X-18796Y-159763D01*
X-19669Y-161805D01*
X-20979Y-162971D01*
X-22289Y-163263D01*
G01X-8501D02*
Y-151597D01*
G01Y-154513D02*
X-7627Y-153055D01*
X-6317Y-151888D01*
X-4571Y-151597D01*
X-3043Y-151888D01*
X-1732Y-153055D01*
X-1077Y-155096D01*
Y-163263D01*
G01X9436Y-155388D02*
X16423D01*
X15768Y-153346D01*
X14676Y-152180D01*
X13148Y-151597D01*
X11619Y-151888D01*
X10309Y-152763D01*
X9436Y-154805D01*
X8999Y-156555D01*
Y-158305D01*
X9436Y-160055D01*
X10528Y-161805D01*
X11838Y-162971D01*
X13366Y-163263D01*
X14894Y-162680D01*
X16423Y-160930D01*
G01X25626Y-168513D02*
X26936Y-169096D01*
X28683Y-168513D01*
X29774Y-167347D01*
X30648Y-165888D01*
X31957Y-161222D01*
X34796Y-151597D01*
G01X27809D02*
X31957Y-161222D01*
G01X66957Y-153930D02*
X67831Y-153055D01*
X68486Y-151597D01*
X68923Y-149554D01*
X68486Y-147805D01*
X67613Y-146638D01*
X66084Y-145763D01*
X60189D01*
Y-163263D01*
X67394D01*
X68923Y-162097D01*
X69796Y-160346D01*
X70233Y-158305D01*
X69796Y-156263D01*
X68486Y-154513D01*
X66957Y-153930D01*
X60189D01*
G01X86641Y-163263D02*
Y-151597D01*
G01Y-153638D02*
X85768Y-152472D01*
X84457Y-151888D01*
X82929Y-151597D01*
X81401Y-152180D01*
X80091Y-153346D01*
X79217Y-155096D01*
X78781Y-157430D01*
X79217Y-159763D01*
X80091Y-161513D01*
X81401Y-162680D01*
X82929Y-163263D01*
X84457Y-162971D01*
X85768Y-162097D01*
X86641Y-160930D01*
G01X104141Y-145763D02*
Y-163263D01*
G01Y-160639D02*
X103268Y-162097D01*
X101957Y-162971D01*
X100429Y-163263D01*
X98683Y-162680D01*
X97373Y-161222D01*
X96499Y-159472D01*
X96281Y-157430D01*
X96499Y-155388D01*
X97373Y-153638D01*
X98683Y-152180D01*
X100429Y-151597D01*
X101957Y-151888D01*
X103049Y-152472D01*
X104141Y-153638D01*
G01X114654Y-167638D02*
X116183Y-168805D01*
X117929Y-169096D01*
X119457Y-168805D01*
X120768Y-167347D01*
X121641Y-165305D01*
Y-151597D01*
G01Y-153930D02*
X120768Y-152763D01*
X119457Y-151888D01*
X117929Y-151597D01*
X116183Y-152180D01*
X115091Y-153346D01*
X114217Y-155388D01*
X113781Y-157430D01*
X113999Y-159180D01*
X114873Y-161222D01*
X116183Y-162680D01*
X117929Y-163263D01*
X119239Y-162971D01*
X120768Y-161805D01*
X121641Y-160639D01*
G01X131936Y-155388D02*
X138923D01*
X138268Y-153346D01*
X137176Y-152180D01*
X135648Y-151597D01*
X134119Y-151888D01*
X132809Y-152763D01*
X131936Y-154805D01*
X131499Y-156555D01*
Y-158305D01*
X131936Y-160055D01*
X133028Y-161805D01*
X134338Y-162971D01*
X135866Y-163263D01*
X137394Y-162680D01*
X138923Y-160930D01*
G01X149654Y-163263D02*
Y-151597D01*
G01Y-153930D02*
X150746Y-152763D01*
X151838Y-151888D01*
X153366Y-151597D01*
X154457Y-151888D01*
X155768Y-152763D01*
G01X183344Y-163263D02*
Y-145763D01*
X188803D01*
X190549Y-146638D01*
X191641Y-147805D01*
X192078Y-150138D01*
X191641Y-152472D01*
X190331Y-153930D01*
X188803Y-154805D01*
X183344D01*
G01X188803D02*
X192078Y-163263D01*
G01X205211Y-151597D02*
Y-163263D01*
G01Y-146930D02*
X204774Y-146638D01*
Y-146055D01*
X205211Y-145763D01*
X205648Y-146055D01*
Y-146638D01*
X205211Y-146930D01*
G01X219436Y-161222D02*
X220528Y-162388D01*
X222056Y-163263D01*
X223366D01*
X224676Y-162680D01*
X225549Y-161805D01*
X225986Y-160639D01*
X225768Y-158888D01*
X224894Y-158013D01*
X220964Y-156263D01*
X220091Y-154221D01*
X220528Y-152763D01*
X221401Y-151888D01*
X222711Y-151597D01*
X224021Y-151888D01*
X225331Y-152763D01*
G01X236936Y-155388D02*
X243923D01*
X243268Y-153346D01*
X242176Y-152180D01*
X240648Y-151597D01*
X239119Y-151888D01*
X237809Y-152763D01*
X236936Y-154805D01*
X236499Y-156555D01*
Y-158305D01*
X236936Y-160055D01*
X238028Y-161805D01*
X239338Y-162971D01*
X240866Y-163263D01*
X242394Y-162680D01*
X243923Y-160930D01*
G01X254654Y-163263D02*
Y-151597D01*
G01Y-153930D02*
X255746Y-152763D01*
X256838Y-151888D01*
X258366Y-151597D01*
X259457Y-151888D01*
X260768Y-152763D01*
G01X297514Y-147222D02*
X296204Y-146346D01*
X294676Y-145763D01*
X292929D01*
X290964Y-146638D01*
X289436Y-148096D01*
X288344Y-149847D01*
X287471Y-152763D01*
X287252Y-155388D01*
X287689Y-158013D01*
X288344Y-159763D01*
X289654Y-161513D01*
X291183Y-162680D01*
X292711Y-163263D01*
X294239D01*
X295768Y-162680D01*
X297078Y-161805D01*
X298170Y-160639D01*
G01X314141Y-163263D02*
Y-151597D01*
G01Y-153638D02*
X313268Y-152472D01*
X311957Y-151888D01*
X310429Y-151597D01*
X308901Y-152180D01*
X307591Y-153346D01*
X306717Y-155096D01*
X306281Y-157430D01*
X306717Y-159763D01*
X307591Y-161513D01*
X308901Y-162680D01*
X310429Y-163263D01*
X311957Y-162971D01*
X313268Y-162097D01*
X314141Y-160930D01*
G01X324654Y-163263D02*
Y-151597D01*
G01Y-153930D02*
X325746Y-152763D01*
X326838Y-151888D01*
X328366Y-151597D01*
X329457Y-151888D01*
X330768Y-152763D01*
G01X349141Y-145763D02*
Y-163263D01*
G01Y-160639D02*
X348268Y-162097D01*
X346957Y-162971D01*
X345429Y-163263D01*
X343683Y-162680D01*
X342373Y-161222D01*
X341499Y-159472D01*
X341281Y-157430D01*
X341499Y-155388D01*
X342373Y-153638D01*
X343683Y-152180D01*
X345429Y-151597D01*
X346957Y-151888D01*
X348049Y-152472D01*
X349141Y-153638D01*
G01X112034Y-118263D02*
Y-100763D01*
X117711Y-115346D01*
X123388Y-100763D01*
Y-118263D01*
G01X135211D02*
X133901Y-117971D01*
X132591Y-116805D01*
X131717Y-114763D01*
X131281Y-112430D01*
X131717Y-110096D01*
X132591Y-108055D01*
X133901Y-106888D01*
X135211Y-106597D01*
X136521Y-106888D01*
X137831Y-108055D01*
X138704Y-110096D01*
X138923Y-112430D01*
X138704Y-114763D01*
X137831Y-116805D01*
X136521Y-117971D01*
X135211Y-118263D01*
G01X156641Y-100763D02*
Y-118263D01*
G01Y-115639D02*
X155768Y-117097D01*
X154457Y-117971D01*
X152929Y-118263D01*
X151183Y-117680D01*
X149873Y-116222D01*
X148999Y-114472D01*
X148781Y-112430D01*
X148999Y-110388D01*
X149873Y-108638D01*
X151183Y-107180D01*
X152929Y-106597D01*
X154457Y-106888D01*
X155549Y-107472D01*
X156641Y-108638D01*
G01X166936Y-110388D02*
X173923D01*
X173268Y-108346D01*
X172176Y-107180D01*
X170648Y-106597D01*
X169119Y-106888D01*
X167809Y-107763D01*
X166936Y-109805D01*
X166499Y-111555D01*
Y-113305D01*
X166936Y-115055D01*
X168028Y-116805D01*
X169338Y-117971D01*
X170866Y-118263D01*
X172394Y-117680D01*
X173923Y-115930D01*
G01X187711Y-118263D02*
Y-100763D01*
G01X402811Y-163263D02*
Y-145763D01*
X400191Y-149263D01*
G01Y-163263D02*
X405431D01*
G01X415508Y-159763D02*
X416817Y-161805D01*
X418564Y-162971D01*
X420529Y-163263D01*
X422276Y-162971D01*
X424023Y-161513D01*
X425114Y-159763D01*
X425333Y-158013D01*
X424896Y-155972D01*
X423368Y-154513D01*
X421839Y-153930D01*
X419874D01*
G01X421839D02*
X423149Y-153055D01*
X424241Y-151597D01*
X424678Y-149847D01*
X424241Y-148096D01*
X423149Y-146638D01*
X421184Y-145763D01*
X419219Y-146055D01*
X417254Y-147222D01*
G01X434099Y-161222D02*
X435628Y-162680D01*
X437374Y-163263D01*
X439121Y-162680D01*
X440649Y-160930D01*
X441741Y-158305D01*
X442178Y-155680D01*
Y-152472D01*
X441741Y-149847D01*
X440649Y-147513D01*
X439339Y-146346D01*
X437811Y-145763D01*
X436064Y-146346D01*
X434754Y-147513D01*
X433881Y-149263D01*
X433444Y-151597D01*
X433881Y-153638D01*
X434973Y-155680D01*
X436283Y-156847D01*
X437811Y-157138D01*
X439557Y-156555D01*
X440868Y-155096D01*
X442178Y-152472D01*
G01X455311Y-163263D02*
Y-145763D01*
X452691Y-149263D01*
G01Y-163263D02*
X457931D01*
G01X469099Y-161222D02*
X470628Y-162680D01*
X472374Y-163263D01*
X474121Y-162680D01*
X475649Y-160930D01*
X476741Y-158305D01*
X477178Y-155680D01*
Y-152472D01*
X476741Y-149847D01*
X475649Y-147513D01*
X474339Y-146346D01*
X472811Y-145763D01*
X471064Y-146346D01*
X469754Y-147513D01*
X468881Y-149263D01*
X468444Y-151597D01*
X468881Y-153638D01*
X469973Y-155680D01*
X471283Y-156847D01*
X472811Y-157138D01*
X474557Y-156555D01*
X475868Y-155096D01*
X477178Y-152472D01*
G01X389694Y-118263D02*
Y-100763D01*
X394934D01*
X396681Y-101638D01*
X397991Y-103680D01*
X398428Y-106013D01*
X397991Y-108346D01*
X396899Y-110096D01*
X394934Y-110972D01*
X389694D01*
G01X416364Y-102222D02*
X415054Y-101346D01*
X413526Y-100763D01*
X411779D01*
X409814Y-101638D01*
X408286Y-103096D01*
X407194Y-104847D01*
X406321Y-107763D01*
X406102Y-110388D01*
X406539Y-113013D01*
X407194Y-114763D01*
X408504Y-116513D01*
X410033Y-117680D01*
X411561Y-118263D01*
X413089D01*
X414618Y-117680D01*
X415928Y-116805D01*
X417020Y-115639D01*
G01X430807Y-108930D02*
X431681Y-108055D01*
X432336Y-106597D01*
X432773Y-104554D01*
X432336Y-102805D01*
X431463Y-101638D01*
X429934Y-100763D01*
X424039D01*
Y-118263D01*
X431244D01*
X432773Y-117097D01*
X433646Y-115346D01*
X434083Y-113305D01*
X433646Y-111263D01*
X432336Y-109513D01*
X430807Y-108930D01*
X424039D01*
G01X440011Y-124096D02*
X453111D01*
G01X459039Y-118263D02*
Y-100763D01*
X469083Y-118263D01*
Y-100763D01*
G01X481561Y-118263D02*
X479814Y-117971D01*
X478286Y-116805D01*
X476976Y-115055D01*
X476102Y-113013D01*
X475666Y-110680D01*
Y-108346D01*
X476102Y-106013D01*
X476976Y-103971D01*
X478286Y-102222D01*
X479814Y-101055D01*
X481561Y-100763D01*
X483307Y-101055D01*
X484836Y-102222D01*
X486146Y-103971D01*
X487020Y-106013D01*
X487456Y-108346D01*
Y-110680D01*
X487020Y-113013D01*
X486146Y-115055D01*
X484836Y-116805D01*
X483307Y-117971D01*
X481561Y-118263D01*
G01X532402Y-100763D02*
X537861Y-118263D01*
X543320Y-100763D01*
G01X559728Y-118263D02*
X550994D01*
Y-100763D01*
X559728D01*
G01X556234Y-109221D02*
X550994D01*
G01X568494Y-118263D02*
Y-100763D01*
X573953D01*
X575699Y-101638D01*
X576791Y-102805D01*
X577228Y-105138D01*
X576791Y-107472D01*
X575481Y-108930D01*
X573953Y-109805D01*
X568494D01*
G01X573953D02*
X577228Y-118263D01*
G01X590361Y-118846D02*
X589924Y-118555D01*
Y-117971D01*
X590361Y-117680D01*
X590798Y-117971D01*
Y-118555D01*
X590361Y-118846D01*
G01X550776Y-160930D02*
X552523Y-162388D01*
X554488Y-163263D01*
X556234D01*
X557981Y-162388D01*
X559291Y-160930D01*
X559946Y-158888D01*
X559509Y-156847D01*
X558418Y-155096D01*
X556453Y-153930D01*
X553833Y-153346D01*
X552304Y-152180D01*
X551649Y-150138D01*
X552086Y-148096D01*
X553178Y-146638D01*
X554706Y-145763D01*
X556234D01*
X557763Y-146346D01*
X559073Y-147805D01*
G01X567402Y-163263D02*
X572861Y-145763D01*
X578320Y-163263D01*
G01X576354Y-157138D02*
X569367D01*
G01X670311Y-145763D02*
Y-163263D01*
G01X665289Y-145763D02*
X675333D01*
G01X683226Y-160930D02*
X684973Y-162388D01*
X686938Y-163263D01*
X688684D01*
X690431Y-162388D01*
X691741Y-160930D01*
X692396Y-158888D01*
X691959Y-156847D01*
X690868Y-155096D01*
X688903Y-153930D01*
X686283Y-153346D01*
X684754Y-152180D01*
X684099Y-150138D01*
X684536Y-148096D01*
X685628Y-146638D01*
X687156Y-145763D01*
X688684D01*
X690213Y-146346D01*
X691523Y-147805D01*
G01X702691Y-145763D02*
X707931D01*
G01X705311D02*
Y-163263D01*
G01X702691D02*
X707931D01*
G01X718444Y-145763D02*
Y-163263D01*
X727178D01*
G01X735508D02*
Y-145763D01*
G01X743804D02*
X735508Y-156555D01*
G01X745114Y-163263D02*
X739219Y-151597D01*
G01X665944Y-100763D02*
Y-118263D01*
X674678D01*
G01X691741D02*
Y-106597D01*
G01Y-108638D02*
X690868Y-107472D01*
X689557Y-106888D01*
X688029Y-106597D01*
X686501Y-107180D01*
X685191Y-108346D01*
X684317Y-110096D01*
X683881Y-112430D01*
X684317Y-114763D01*
X685191Y-116513D01*
X686501Y-117680D01*
X688029Y-118263D01*
X689557Y-117971D01*
X690868Y-117097D01*
X691741Y-115930D01*
G01X700726Y-123513D02*
X702036Y-124096D01*
X703783Y-123513D01*
X704874Y-122347D01*
X705748Y-120888D01*
X707057Y-116222D01*
X709896Y-106597D01*
G01X702909D02*
X707057Y-116222D01*
G01X719536Y-110388D02*
X726523D01*
X725868Y-108346D01*
X724776Y-107180D01*
X723248Y-106597D01*
X721719Y-106888D01*
X720409Y-107763D01*
X719536Y-109805D01*
X719099Y-111555D01*
Y-113305D01*
X719536Y-115055D01*
X720628Y-116805D01*
X721938Y-117971D01*
X723466Y-118263D01*
X724994Y-117680D01*
X726523Y-115930D01*
G01X737254Y-118263D02*
Y-106597D01*
G01Y-108930D02*
X738346Y-107763D01*
X739438Y-106888D01*
X740966Y-106597D01*
X742057Y-106888D01*
X743368Y-107763D01*
G01X808058Y-118263D02*
Y-100763D01*
X812424D01*
X814171Y-101638D01*
X815481Y-102805D01*
X816573Y-104554D01*
X817446Y-106597D01*
X817664Y-109513D01*
X817446Y-112430D01*
X816573Y-114472D01*
X815481Y-116222D01*
X814171Y-117388D01*
X812424Y-118263D01*
X808058D01*
G01X827086Y-110388D02*
X834073D01*
X833418Y-108346D01*
X832326Y-107180D01*
X830798Y-106597D01*
X829269Y-106888D01*
X827959Y-107763D01*
X827086Y-109805D01*
X826649Y-111555D01*
Y-113305D01*
X827086Y-115055D01*
X828178Y-116805D01*
X829488Y-117971D01*
X831016Y-118263D01*
X832544Y-117680D01*
X834073Y-115930D01*
G01X844586Y-116222D02*
X845678Y-117388D01*
X847206Y-118263D01*
X848516D01*
X849826Y-117680D01*
X850699Y-116805D01*
X851136Y-115639D01*
X850918Y-113888D01*
X850044Y-113013D01*
X846114Y-111263D01*
X845241Y-109221D01*
X845678Y-107763D01*
X846551Y-106888D01*
X847861Y-106597D01*
X849171Y-106888D01*
X850481Y-107763D01*
G01X865361Y-106597D02*
Y-118263D01*
G01Y-101930D02*
X864924Y-101638D01*
Y-101055D01*
X865361Y-100763D01*
X865798Y-101055D01*
Y-101638D01*
X865361Y-101930D01*
G01X879804Y-122638D02*
X881333Y-123805D01*
X883079Y-124096D01*
X884607Y-123805D01*
X885918Y-122347D01*
X886791Y-120305D01*
Y-106597D01*
G01Y-108930D02*
X885918Y-107763D01*
X884607Y-106888D01*
X883079Y-106597D01*
X881333Y-107180D01*
X880241Y-108346D01*
X879367Y-110388D01*
X878931Y-112430D01*
X879149Y-114180D01*
X880023Y-116222D01*
X881333Y-117680D01*
X883079Y-118263D01*
X884389Y-117971D01*
X885918Y-116805D01*
X886791Y-115639D01*
G01X896649Y-118263D02*
Y-106597D01*
G01Y-109513D02*
X897523Y-108055D01*
X898833Y-106888D01*
X900579Y-106597D01*
X902107Y-106888D01*
X903418Y-108055D01*
X904073Y-110096D01*
Y-118263D01*
G01X914586Y-110388D02*
X921573D01*
X920918Y-108346D01*
X919826Y-107180D01*
X918298Y-106597D01*
X916769Y-106888D01*
X915459Y-107763D01*
X914586Y-109805D01*
X914149Y-111555D01*
Y-113305D01*
X914586Y-115055D01*
X915678Y-116805D01*
X916988Y-117971D01*
X918516Y-118263D01*
X920044Y-117680D01*
X921573Y-115930D01*
G01X932304Y-118263D02*
Y-106597D01*
G01Y-108930D02*
X933396Y-107763D01*
X934488Y-106888D01*
X936016Y-106597D01*
X937107Y-106888D01*
X938418Y-107763D01*
G01X853991Y-145763D02*
X859231D01*
G01X856611D02*
Y-163263D01*
G01X853991D02*
X859231D01*
G01X868652Y-145763D02*
X874111Y-163263D01*
X879570Y-145763D01*
G01X891611Y-163263D02*
Y-155388D01*
X887244Y-145763D01*
G01X895978D02*
X891611Y-155388D01*
G01X979061Y-163263D02*
Y-145763D01*
X976441Y-149263D01*
G01Y-163263D02*
X981681D01*
G01X996561D02*
Y-145763D01*
X993941Y-149263D01*
G01Y-163263D02*
X999181D01*
G01X1010131Y-163846D02*
X1017991Y-145763D01*
G01X1027413Y-148680D02*
X1028723Y-146930D01*
X1030251Y-146055D01*
X1031998Y-145763D01*
X1034181Y-146346D01*
X1035709Y-147805D01*
X1036146Y-149554D01*
X1035928Y-151305D01*
X1035054Y-152763D01*
X1030688Y-155680D01*
X1028723Y-157721D01*
X1027413Y-160639D01*
X1026976Y-163263D01*
X1036146D01*
G01X1044913Y-148680D02*
X1046223Y-146930D01*
X1047751Y-146055D01*
X1049498Y-145763D01*
X1051681Y-146346D01*
X1053209Y-147805D01*
X1053646Y-149554D01*
X1053428Y-151305D01*
X1052554Y-152763D01*
X1048188Y-155680D01*
X1046223Y-157721D01*
X1044913Y-160639D01*
X1044476Y-163263D01*
X1053646D01*
G01X1062631Y-163846D02*
X1070491Y-145763D01*
G01X1079913Y-148680D02*
X1081223Y-146930D01*
X1082751Y-146055D01*
X1084498Y-145763D01*
X1086681Y-146346D01*
X1088209Y-147805D01*
X1088646Y-149554D01*
X1088428Y-151305D01*
X1087554Y-152763D01*
X1083188Y-155680D01*
X1081223Y-157721D01*
X1079913Y-160639D01*
X1079476Y-163263D01*
X1088646D01*
G01X1101561Y-145763D02*
X1099814Y-146346D01*
X1098504Y-147805D01*
X1097631Y-149554D01*
X1096976Y-151888D01*
X1096758Y-154513D01*
X1096976Y-157138D01*
X1097631Y-159472D01*
X1098504Y-161222D01*
X1099814Y-162680D01*
X1101561Y-163263D01*
X1103307Y-162680D01*
X1104618Y-161222D01*
X1105491Y-159472D01*
X1106146Y-157138D01*
X1106364Y-154513D01*
X1106146Y-151888D01*
X1105491Y-149554D01*
X1104618Y-147805D01*
X1103307Y-146346D01*
X1101561Y-145763D01*
G01X1119061Y-163263D02*
Y-145763D01*
X1116441Y-149263D01*
G01Y-163263D02*
X1121681D01*
G01X1131758Y-159763D02*
X1133067Y-161805D01*
X1134814Y-162971D01*
X1136779Y-163263D01*
X1138526Y-162971D01*
X1140273Y-161513D01*
X1141364Y-159763D01*
X1141583Y-158013D01*
X1141146Y-155972D01*
X1139618Y-154513D01*
X1138089Y-153930D01*
X1136124D01*
G01X1138089D02*
X1139399Y-153055D01*
X1140491Y-151597D01*
X1140928Y-149847D01*
X1140491Y-148096D01*
X1139399Y-146638D01*
X1137434Y-145763D01*
X1135469Y-146055D01*
X1133504Y-147222D01*
G01X1026758Y-118263D02*
Y-100763D01*
X1031124D01*
X1032871Y-101638D01*
X1034181Y-102805D01*
X1035273Y-104554D01*
X1036146Y-106597D01*
X1036364Y-109513D01*
X1036146Y-112430D01*
X1035273Y-114472D01*
X1034181Y-116222D01*
X1032871Y-117388D01*
X1031124Y-118263D01*
X1026758D01*
G01X1052991D02*
Y-106597D01*
G01Y-108638D02*
X1052118Y-107472D01*
X1050807Y-106888D01*
X1049279Y-106597D01*
X1047751Y-107180D01*
X1046441Y-108346D01*
X1045567Y-110096D01*
X1045131Y-112430D01*
X1045567Y-114763D01*
X1046441Y-116513D01*
X1047751Y-117680D01*
X1049279Y-118263D01*
X1050807Y-117971D01*
X1052118Y-117097D01*
X1052991Y-115930D01*
G01X1066561Y-100763D02*
Y-118263D01*
G01X1063504Y-106597D02*
X1069618D01*
G01X1080786Y-110388D02*
X1087773D01*
X1087118Y-108346D01*
X1086026Y-107180D01*
X1084498Y-106597D01*
X1082969Y-106888D01*
X1081659Y-107763D01*
X1080786Y-109805D01*
X1080349Y-111555D01*
Y-113305D01*
X1080786Y-115055D01*
X1081878Y-116805D01*
X1083188Y-117971D01*
X1084716Y-118263D01*
X1086244Y-117680D01*
X1087773Y-115930D01*
G01X27818Y29800D02*
X30068D01*
G01X27818Y23920D02*
Y29800D01*
G01X30068Y23920D02*
X27818D01*
G01X29168Y26955D02*
X27818D01*
G01X33568Y25590D02*
Y29800D01*
G01X33338Y24705D02*
X33568Y25590D01*
G01X32888Y24120D02*
X33338Y24705D01*
G01X32323Y23920D02*
X32888Y24120D01*
G01X31758D02*
X32323Y23920D01*
G01X31308Y24705D02*
X31758Y24120D01*
G01X31083Y25590D02*
X31308Y24705D01*
G01X31083Y29800D02*
Y25590D01*
G01X39533Y24015D02*
X39088Y23920D01*
G01X39933Y24410D02*
X39533Y24015D01*
G01X40268Y25000D02*
X39933Y24410D01*
G01X40498Y25685D02*
X40268Y25000D01*
G01X40608Y26470D02*
X40498Y25685D01*
G01X40608Y27250D02*
Y26470D01*
G01X40498Y28035D02*
X40608Y27250D01*
G01X40268Y28720D02*
X40498Y28035D01*
G01X39933Y29310D02*
X40268Y28720D01*
G01X39533Y29705D02*
X39933Y29310D01*
G01X39088Y29800D02*
X39533Y29705D01*
G01X38638D02*
X39088Y29800D01*
G01X38238Y29310D02*
X38638Y29705D01*
G01X37903Y28720D02*
X38238Y29310D01*
G01X37673Y28035D02*
X37903Y28720D01*
G01X37563Y27250D02*
X37673Y28035D01*
G01X37563Y26470D02*
Y27250D01*
G01X37673Y25685D02*
X37563Y26470D01*
G01X37903Y25000D02*
X37673Y25685D01*
G01X38238Y24410D02*
X37903Y25000D01*
G01X38638Y24015D02*
X38238Y24410D01*
G01X39088Y23920D02*
X38638Y24015D01*
G01X41513Y23920D02*
Y27840D01*
G01X43423Y26660D02*
Y23920D01*
G01X43253Y27350D02*
X43423Y26660D01*
G01X42913Y27740D02*
X43253Y27350D01*
G01X42523Y27840D02*
X42913Y27740D01*
G01X42068D02*
X42523Y27840D01*
G01X41733Y27350D02*
X42068Y27740D01*
G01X41513Y26860D02*
X41733Y27350D01*
G01X45848Y23920D02*
Y29800D01*
G01X4471Y36808D02*
Y44608D01*
X17071D01*
Y36808D01*
X4471D01*
G01X7971Y43208D02*
X7371Y43108D01*
X6871Y42608D01*
X6471Y42108D01*
X6271Y41508D01*
X6171Y40708D01*
X6271Y40008D01*
X6471Y39308D01*
X6871Y38808D01*
X7371Y38408D01*
X7971Y38208D01*
X8671Y38408D01*
X9171Y38808D01*
X9471Y39308D01*
X9771Y40008D01*
X9871Y40708D01*
X9771Y41508D01*
X9471Y42108D01*
X9171Y42608D01*
X8671Y43108D01*
X7971Y43208D01*
G01X13571Y38208D02*
Y43208D01*
X12571Y42208D01*
G01Y38208D02*
X14571D01*
G01X20917Y60002D02*
X20667Y60127D01*
X20375Y60210D01*
X20042D01*
X19667Y60085D01*
X19375Y59877D01*
X19167Y59627D01*
X19000Y59210D01*
X18958Y58835D01*
X19042Y58460D01*
X19167Y58210D01*
X19417Y57960D01*
X19708Y57793D01*
X20000Y57710D01*
X20292D01*
X20583Y57793D01*
X20833Y57918D01*
X21042Y58085D01*
G01X22142Y57710D02*
Y60210D01*
X24058Y57710D01*
Y60210D01*
G01X26200Y57710D02*
Y60210D01*
X25700Y59710D01*
G01Y57710D02*
X26700D01*
G01X363228Y99446D02*
Y62446D01*
X10828D01*
Y99446D01*
X363228D01*
G01X4470Y271848D02*
Y279648D01*
X17070D01*
Y271848D01*
X4470D01*
G01X7970Y278248D02*
X7370Y278148D01*
X6870Y277648D01*
X6470Y277148D01*
X6270Y276548D01*
X6170Y275748D01*
X6270Y275048D01*
X6470Y274348D01*
X6870Y273848D01*
X7370Y273448D01*
X7970Y273248D01*
X8670Y273448D01*
X9170Y273848D01*
X9470Y274348D01*
X9770Y275048D01*
X9870Y275748D01*
X9770Y276548D01*
X9470Y277148D01*
X9170Y277648D01*
X8670Y278148D01*
X7970Y278248D01*
G01X11770Y274048D02*
X12270Y273648D01*
X12870Y273348D01*
X13570Y273248D01*
X14370Y273448D01*
X14970Y273748D01*
X15370Y274348D01*
X15470Y275048D01*
X15270Y275648D01*
X14870Y276148D01*
X14270Y276448D01*
X13670Y276548D01*
X13070Y276448D01*
X12370Y276148D01*
X12570Y278248D01*
X14870D01*
G01X4470Y506887D02*
Y514687D01*
X17070D01*
Y506887D01*
X4470D01*
G01X7970Y513287D02*
X7370Y513187D01*
X6870Y512687D01*
X6470Y512187D01*
X6270Y511587D01*
X6170Y510787D01*
X6270Y510087D01*
X6470Y509387D01*
X6870Y508887D01*
X7370Y508487D01*
X7970Y508287D01*
X8670Y508487D01*
X9170Y508887D01*
X9470Y509387D01*
X9770Y510087D01*
X9870Y510787D01*
X9770Y511587D01*
X9470Y512187D01*
X9170Y512687D01*
X8670Y513187D01*
X7970Y513287D01*
G01X12170Y508887D02*
X12770Y508487D01*
X13470Y508287D01*
X14070Y508487D01*
X14670Y508987D01*
X15070Y509687D01*
X15270Y510487D01*
Y511387D01*
X15070Y512187D01*
X14670Y512787D01*
X14170Y513187D01*
X13570Y513287D01*
X12970Y513187D01*
X12470Y512787D01*
X12070Y512287D01*
X11970Y511687D01*
X12070Y511087D01*
X12470Y510487D01*
X12970Y510187D01*
X13570Y510087D01*
X14270Y510187D01*
X14770Y510687D01*
X15270Y511387D01*
G01X49678Y24605D02*
X50413Y27840D01*
G01X49338Y23040D02*
X49678Y24605D01*
G01X49118Y22545D02*
X49338Y23040D01*
G01X48833Y22155D02*
X49118Y22545D01*
G01X48383Y21960D02*
X48833Y22155D01*
G01X48043D02*
X48383Y21960D01*
G01X48613Y27840D02*
X49678Y24605D01*
G01X286980Y32320D02*
X287813D01*
Y31570D01*
X287563Y31320D01*
X287272Y31153D01*
X286855Y31070D01*
X286438Y31153D01*
X286147Y31320D01*
X285897Y31570D01*
X285730Y31862D01*
X285647Y32195D01*
Y32487D01*
X285730Y32737D01*
X285897Y33028D01*
X286147Y33278D01*
X286397Y33445D01*
X286730Y33570D01*
X287022D01*
X287355Y33487D01*
X287605Y33320D01*
G01X289038Y31070D02*
Y33570D01*
X290622D01*
G01X290038Y32362D02*
X289038D01*
G01X292138Y33153D02*
X292388Y33403D01*
X292680Y33528D01*
X293013Y33570D01*
X293430Y33487D01*
X293722Y33278D01*
X293805Y33028D01*
X293763Y32778D01*
X293597Y32570D01*
X292763Y32153D01*
X292388Y31862D01*
X292138Y31445D01*
X292055Y31070D01*
X293805D01*
G01X386361Y36808D02*
Y44608D01*
X398961D01*
Y36808D01*
X386361D01*
G01X389861Y43208D02*
X389261Y43108D01*
X388761Y42608D01*
X388361Y42108D01*
X388161Y41508D01*
X388061Y40708D01*
X388161Y40008D01*
X388361Y39308D01*
X388761Y38808D01*
X389261Y38408D01*
X389861Y38208D01*
X390561Y38408D01*
X391061Y38808D01*
X391361Y39308D01*
X391661Y40008D01*
X391761Y40708D01*
X391661Y41508D01*
X391361Y42108D01*
X391061Y42608D01*
X390561Y43108D01*
X389861Y43208D01*
G01X393861Y42408D02*
X394361Y42908D01*
X394961Y43108D01*
X395661Y43208D01*
X396461Y43108D01*
X397061Y42608D01*
X397261Y42108D01*
X397161Y41608D01*
X396861Y41208D01*
X395161Y40408D01*
X394361Y39808D01*
X393861Y39008D01*
X393761Y38208D01*
X397261D01*
G01X369545Y184452D02*
Y176652D01*
X356945D01*
Y184452D01*
X369545D01*
G01X366045Y178052D02*
X366645Y178152D01*
X367145Y178652D01*
X367545Y179152D01*
X367745Y179752D01*
X367845Y180552D01*
X367745Y181252D01*
X367545Y181952D01*
X367145Y182452D01*
X366645Y182852D01*
X366045Y183052D01*
X365345Y182852D01*
X364845Y182452D01*
X364545Y181952D01*
X364245Y181252D01*
X364145Y180552D01*
X364245Y179752D01*
X364545Y179152D01*
X364845Y178652D01*
X365345Y178152D01*
X366045Y178052D01*
G01X362245Y182052D02*
X361745Y182652D01*
X361045Y182952D01*
X360345Y183052D01*
X359645Y182952D01*
X359045Y182552D01*
X358545Y182052D01*
Y181552D01*
X358645Y180952D01*
X359245Y180552D01*
X359845Y180352D01*
X360545D01*
G01X359845D02*
X359345Y180152D01*
X358945Y179652D01*
X358745Y179152D01*
X358945Y178652D01*
X359345Y178252D01*
X360045Y178052D01*
X360845Y178152D01*
X361545Y178452D01*
G01X386360Y271848D02*
Y279648D01*
X398960D01*
Y271848D01*
X386360D01*
G01X389860Y278248D02*
X389260Y278148D01*
X388760Y277648D01*
X388360Y277148D01*
X388160Y276548D01*
X388060Y275748D01*
X388160Y275048D01*
X388360Y274348D01*
X388760Y273848D01*
X389260Y273448D01*
X389860Y273248D01*
X390560Y273448D01*
X391060Y273848D01*
X391360Y274348D01*
X391660Y275048D01*
X391760Y275748D01*
X391660Y276548D01*
X391360Y277148D01*
X391060Y277648D01*
X390560Y278148D01*
X389860Y278248D01*
G01X393860Y275348D02*
X394460Y275948D01*
X394960Y276248D01*
X395660Y276448D01*
X396260Y276248D01*
X396660Y275948D01*
X396960Y275448D01*
X397060Y274848D01*
X396960Y274348D01*
X396660Y273848D01*
X396160Y273448D01*
X395560Y273248D01*
X394860Y273448D01*
X394360Y273948D01*
X393960Y274648D01*
X393860Y275548D01*
X394060Y276648D01*
X394360Y277148D01*
X394760Y277748D01*
X395360Y278148D01*
X395860Y278248D01*
X396460Y278148D01*
X396860Y277648D01*
G01X369545Y419491D02*
Y411691D01*
X356945D01*
Y419491D01*
X369545D01*
G01X366045Y413091D02*
X366645Y413191D01*
X367145Y413691D01*
X367545Y414191D01*
X367745Y414791D01*
X367845Y415591D01*
X367745Y416291D01*
X367545Y416991D01*
X367145Y417491D01*
X366645Y417891D01*
X366045Y418091D01*
X365345Y417891D01*
X364845Y417491D01*
X364545Y416991D01*
X364245Y416291D01*
X364145Y415591D01*
X364245Y414791D01*
X364545Y414191D01*
X364845Y413691D01*
X365345Y413191D01*
X366045Y413091D01*
G01X360545Y418091D02*
X360445Y416991D01*
X359845Y415191D01*
X359445Y414291D01*
X358745Y413091D01*
X362045D01*
G01X386360Y506887D02*
Y514687D01*
X398960D01*
Y506887D01*
X386360D01*
G01X389860Y508287D02*
Y513287D01*
X388860Y512287D01*
G01Y508287D02*
X390860D01*
G01X395460Y513287D02*
X394860Y513187D01*
X394360Y512687D01*
X393960Y512187D01*
X393760Y511587D01*
X393660Y510787D01*
X393760Y510087D01*
X393960Y509387D01*
X394360Y508887D01*
X394860Y508487D01*
X395460Y508287D01*
X396160Y508487D01*
X396660Y508887D01*
X396960Y509387D01*
X397260Y510087D01*
X397360Y510787D01*
X397260Y511587D01*
X396960Y512187D01*
X396660Y512687D01*
X396160Y513187D01*
X395460Y513287D01*
G01X369545Y654531D02*
Y646731D01*
X356945D01*
Y654531D01*
X369545D01*
G01X366045Y653131D02*
Y648131D01*
X367045Y649131D01*
G01X360445Y653131D02*
Y648131D01*
X361445Y649131D01*
G01X367045Y653131D02*
X365045D01*
G01X361445D02*
X359445D01*
G01X751435Y184452D02*
Y176652D01*
X738835D01*
Y184452D01*
X751435D01*
G01X747935Y178052D02*
X748535Y178152D01*
X749035Y178652D01*
X749435Y179152D01*
X749635Y179752D01*
X749735Y180552D01*
X749635Y181252D01*
X749435Y181952D01*
X749035Y182452D01*
X748535Y182852D01*
X747935Y183052D01*
X747235Y182852D01*
X746735Y182452D01*
X746435Y181952D01*
X746135Y181252D01*
X746035Y180552D01*
X746135Y179752D01*
X746435Y179152D01*
X746735Y178652D01*
X747235Y178152D01*
X747935Y178052D01*
G01X741335Y183052D02*
Y178052D01*
X744435Y181652D01*
X740235D01*
G01X770359Y376653D02*
X770826Y377119D01*
X771226Y377386D01*
X771759Y377519D01*
X772226Y377386D01*
X772559Y377119D01*
X772826Y376719D01*
X772893Y376253D01*
X772826Y375853D01*
X772559Y375453D01*
X772159Y375119D01*
X771693Y374986D01*
X771159Y375119D01*
X770693Y375519D01*
X770426Y376119D01*
X770359Y376786D01*
X770493Y377653D01*
X770693Y378119D01*
X771026Y378586D01*
X771493Y378919D01*
X771959Y378986D01*
X772426Y378853D01*
X772759Y378519D01*
G01X770241Y405748D02*
X770641Y405415D01*
X771108Y405215D01*
X771708Y405148D01*
X772308Y405281D01*
X772775Y405548D01*
X773108Y406015D01*
X773175Y406548D01*
X773041Y407081D01*
X772708Y407415D01*
X772241Y407681D01*
X771775Y407748D01*
X771308Y407681D01*
X770708Y407415D01*
X770908Y409148D01*
X772708D01*
G01X751435Y419491D02*
Y411691D01*
X738835D01*
Y419491D01*
X751435D01*
G01X747935Y413091D02*
X748535Y413191D01*
X749035Y413691D01*
X749435Y414191D01*
X749635Y414791D01*
X749735Y415591D01*
X749635Y416291D01*
X749435Y416991D01*
X749035Y417491D01*
X748535Y417891D01*
X747935Y418091D01*
X747235Y417891D01*
X746735Y417491D01*
X746435Y416991D01*
X746135Y416291D01*
X746035Y415591D01*
X746135Y414791D01*
X746435Y414191D01*
X746735Y413691D01*
X747235Y413191D01*
X747935Y413091D01*
G01X742335Y418091D02*
X741735Y417991D01*
X741035Y417691D01*
X740635Y417291D01*
X740435Y416691D01*
X740635Y416191D01*
X741135Y415691D01*
X741935Y415391D01*
X742735D01*
X743235Y415191D01*
X743635Y414791D01*
X743835Y414191D01*
X743535Y413691D01*
X742935Y413191D01*
X742335Y413091D01*
X741635Y413191D01*
X741035Y413691D01*
X740835Y414191D01*
X740935Y414791D01*
X741435Y415191D01*
X741935Y415391D01*
X742735D01*
X743435Y415691D01*
X743935Y416191D01*
X744135Y416691D01*
X743935Y417291D01*
X743535Y417691D01*
X742935Y417991D01*
X742335Y418091D01*
G01X772953Y437095D02*
Y441095D01*
X770486Y438228D01*
X773820D01*
G01X770449Y469413D02*
X770849Y468946D01*
X771383Y468680D01*
X771983Y468613D01*
X772516Y468680D01*
X773049Y469013D01*
X773383Y469413D01*
X773449Y469813D01*
X773316Y470280D01*
X772849Y470613D01*
X772383Y470746D01*
X771783D01*
G01X772383D02*
X772783Y470946D01*
X773116Y471280D01*
X773249Y471680D01*
X773116Y472080D01*
X772783Y472413D01*
X772183Y472613D01*
X771583Y472546D01*
X770983Y472280D01*
G01X770899Y503675D02*
X771299Y504075D01*
X771766Y504275D01*
X772299Y504342D01*
X772966Y504209D01*
X773433Y503875D01*
X773566Y503475D01*
X773499Y503075D01*
X773233Y502742D01*
X771899Y502075D01*
X771299Y501609D01*
X770899Y500942D01*
X770766Y500342D01*
X773566D01*
G01X771528Y531889D02*
Y535889D01*
X770728Y535089D01*
G01Y531889D02*
X772328D01*
G01X751435Y654531D02*
Y646731D01*
X738835D01*
Y654531D01*
X751435D01*
G01X747935Y653131D02*
Y648131D01*
X748935Y649131D01*
G01X743935Y648931D02*
X743435Y648431D01*
X742835Y648231D01*
X742135Y648131D01*
X741335Y648231D01*
X740735Y648731D01*
X740535Y649231D01*
X740635Y649731D01*
X740935Y650131D01*
X742635Y650931D01*
X743435Y651531D01*
X743935Y652331D01*
X744035Y653131D01*
X740535D01*
G01X748935D02*
X746935D01*
G54D15*
G01X111523Y40330D02*
Y46330D01*
X110323Y45130D01*
G01Y40330D02*
X112723D01*
G01X115923Y41530D02*
X116523Y40830D01*
X117323Y40430D01*
X118223Y40330D01*
X119023Y40430D01*
X119823Y40930D01*
X120323Y41530D01*
X120423Y42130D01*
X120223Y42830D01*
X119523Y43330D01*
X118823Y43530D01*
X117923D01*
G01X118823D02*
X119423Y43830D01*
X119923Y44330D01*
X120123Y44930D01*
X119923Y45530D01*
X119423Y46030D01*
X118523Y46330D01*
X117623Y46230D01*
X116723Y45830D01*
G01X123023Y41030D02*
X123723Y40530D01*
X124523Y40330D01*
X125323Y40530D01*
X126023Y41130D01*
X126523Y42030D01*
X126723Y42930D01*
Y44030D01*
X126523Y44930D01*
X126023Y45730D01*
X125423Y46130D01*
X124723Y46330D01*
X123923Y46130D01*
X123323Y45730D01*
X122923Y45130D01*
X122723Y44330D01*
X122923Y43630D01*
X123423Y42930D01*
X124023Y42530D01*
X124723Y42430D01*
X125523Y42630D01*
X126123Y43130D01*
X126723Y44030D01*
G01X131323Y40330D02*
Y46330D01*
X130123Y45130D01*
G01Y40330D02*
X132523D01*
G01X136223Y41030D02*
X136923Y40530D01*
X137723Y40330D01*
X138523Y40530D01*
X139223Y41130D01*
X139723Y42030D01*
X139923Y42930D01*
Y44030D01*
X139723Y44930D01*
X139223Y45730D01*
X138623Y46130D01*
X137923Y46330D01*
X137123Y46130D01*
X136523Y45730D01*
X136123Y45130D01*
X135923Y44330D01*
X136123Y43630D01*
X136623Y42930D01*
X137223Y42530D01*
X137923Y42430D01*
X138723Y42630D01*
X139323Y43130D01*
X139923Y44030D01*
G01X143223Y42330D02*
X145823D01*
G01X149023Y41130D02*
X149823Y40630D01*
X150723Y40330D01*
X151523D01*
X152323Y40630D01*
X152923Y41130D01*
X153223Y41830D01*
X153023Y42530D01*
X152523Y43130D01*
X151623Y43530D01*
X150423Y43730D01*
X149723Y44130D01*
X149423Y44830D01*
X149623Y45530D01*
X150123Y46030D01*
X150823Y46330D01*
X151523D01*
X152223Y46130D01*
X152823Y45630D01*
G01X155223Y40330D02*
X157723Y46330D01*
X160223Y40330D01*
G01X159323Y42430D02*
X156123D01*
G01X94783Y28990D02*
Y34990D01*
X91083Y30690D01*
X96083D01*
G01X100183Y28990D02*
X100883Y29090D01*
X101683Y29390D01*
X102183Y29890D01*
X102383Y30590D01*
X102183Y31290D01*
X101583Y31890D01*
X100683Y32190D01*
X99683D01*
X99083Y32390D01*
X98583Y32890D01*
X98383Y33590D01*
X98683Y34290D01*
X99383Y34790D01*
X100183Y34990D01*
X100983Y34790D01*
X101683Y34290D01*
X101983Y33590D01*
X101783Y32890D01*
X101283Y32390D01*
X100683Y32190D01*
X99683D01*
X98783Y31890D01*
X98183Y31290D01*
X97983Y30590D01*
X98183Y29890D01*
X98683Y29390D01*
X99483Y29090D01*
X100183Y28990D01*
G01X106783Y28790D02*
X106583Y28890D01*
Y29090D01*
X106783Y29190D01*
X106983Y29090D01*
Y28890D01*
X106783Y28790D01*
G01X114183Y32190D02*
X114583Y32490D01*
X114883Y32990D01*
X115083Y33690D01*
X114883Y34290D01*
X114483Y34690D01*
X113783Y34990D01*
X111083D01*
Y28990D01*
X114383D01*
X115083Y29390D01*
X115483Y29990D01*
X115683Y30690D01*
X115483Y31390D01*
X114883Y31990D01*
X114183Y32190D01*
X111083D01*
G01X119983Y34990D02*
X119183Y34790D01*
X118583Y34290D01*
X118183Y33690D01*
X117883Y32890D01*
X117783Y31990D01*
X117883Y31090D01*
X118183Y30290D01*
X118583Y29690D01*
X119183Y29190D01*
X119983Y28990D01*
X120783Y29190D01*
X121383Y29690D01*
X121783Y30290D01*
X122083Y31090D01*
X122183Y31990D01*
X122083Y32890D01*
X121783Y33690D01*
X121383Y34290D01*
X120783Y34790D01*
X119983Y34990D01*
G01X126383Y28990D02*
X126583Y30290D01*
X126883Y31390D01*
X127283Y32390D01*
X127783Y33490D01*
X128583Y34990D01*
X124583D01*
G01X131283Y33990D02*
X131883Y34590D01*
X132583Y34890D01*
X133383Y34990D01*
X134383Y34790D01*
X135083Y34290D01*
X135283Y33690D01*
X135183Y33090D01*
X134783Y32590D01*
X132783Y31590D01*
X131883Y30890D01*
X131283Y29890D01*
X131083Y28990D01*
X135283D01*
G01X137883Y33990D02*
X138483Y34590D01*
X139183Y34890D01*
X139983Y34990D01*
X140983Y34790D01*
X141683Y34290D01*
X141883Y33690D01*
X141783Y33090D01*
X141383Y32590D01*
X139383Y31590D01*
X138483Y30890D01*
X137883Y29890D01*
X137683Y28990D01*
X141883D01*
G01X146383Y28790D02*
X146183Y28890D01*
Y29090D01*
X146383Y29190D01*
X146583Y29090D01*
Y28890D01*
X146383Y28790D01*
G01X152983Y34990D02*
X152183Y34790D01*
X151583Y34290D01*
X151183Y33690D01*
X150883Y32890D01*
X150783Y31990D01*
X150883Y31090D01*
X151183Y30290D01*
X151583Y29690D01*
X152183Y29190D01*
X152983Y28990D01*
X153783Y29190D01*
X154383Y29690D01*
X154783Y30290D01*
X155083Y31090D01*
X155183Y31990D01*
X155083Y32890D01*
X154783Y33690D01*
X154383Y34290D01*
X153783Y34790D01*
X152983Y34990D01*
G01X157483Y29790D02*
X158283Y29290D01*
X159183Y28990D01*
X159983D01*
X160783Y29290D01*
X161383Y29790D01*
X161683Y30490D01*
X161483Y31190D01*
X160983Y31790D01*
X160083Y32190D01*
X158883Y32390D01*
X158183Y32790D01*
X157883Y33490D01*
X158083Y34190D01*
X158583Y34690D01*
X159283Y34990D01*
X159983D01*
X160683Y34790D01*
X161283Y34290D01*
G01X163683Y28990D02*
X166183Y34990D01*
X168683Y28990D01*
G01X167783Y31090D02*
X164583D01*
G01X62993Y51670D02*
Y57670D01*
G01X67193D02*
Y51670D01*
G01Y54670D02*
X62993D01*
G01X71693Y51670D02*
X71093Y51770D01*
X70493Y52170D01*
X70093Y52870D01*
X69893Y53670D01*
X70093Y54470D01*
X70493Y55170D01*
X71093Y55570D01*
X71693Y55670D01*
X72293Y55570D01*
X72893Y55170D01*
X73293Y54470D01*
X73393Y53670D01*
X73293Y52870D01*
X72893Y52170D01*
X72293Y51770D01*
X71693Y51670D01*
G01X76593D02*
Y55670D01*
G01Y54670D02*
X76993Y55170D01*
X77593Y55570D01*
X78393Y55670D01*
X79093Y55570D01*
X79693Y55170D01*
X79993Y54470D01*
Y51670D01*
G01X83393Y54370D02*
X86593D01*
X86293Y55070D01*
X85793Y55470D01*
X85093Y55670D01*
X84393Y55570D01*
X83793Y55270D01*
X83393Y54570D01*
X83193Y53970D01*
Y53370D01*
X83393Y52770D01*
X83893Y52170D01*
X84493Y51770D01*
X85193Y51670D01*
X85893Y51870D01*
X86593Y52470D01*
G01X89393Y49870D02*
X89993Y49670D01*
X90793Y49870D01*
X91293Y50270D01*
X91693Y50770D01*
X92293Y52370D01*
X93593Y55670D01*
G01X90393D02*
X92293Y52370D01*
G01X105493Y54870D02*
X105893Y55170D01*
X106193Y55670D01*
X106393Y56370D01*
X106193Y56970D01*
X105793Y57370D01*
X105093Y57670D01*
X102393D01*
Y51670D01*
X105693D01*
X106393Y52070D01*
X106793Y52670D01*
X106993Y53370D01*
X106793Y54070D01*
X106193Y54670D01*
X105493Y54870D01*
X102393D01*
G01X113093Y51670D02*
Y55670D01*
G01Y54970D02*
X112693Y55370D01*
X112093Y55570D01*
X111393Y55670D01*
X110693Y55470D01*
X110093Y55070D01*
X109693Y54470D01*
X109493Y53670D01*
X109693Y52870D01*
X110093Y52270D01*
X110693Y51870D01*
X111393Y51670D01*
X112093Y51770D01*
X112693Y52070D01*
X113093Y52470D01*
G01X119693Y57670D02*
Y51670D01*
G01Y52570D02*
X119293Y52070D01*
X118693Y51770D01*
X117993Y51670D01*
X117193Y51870D01*
X116593Y52370D01*
X116193Y52970D01*
X116093Y53670D01*
X116193Y54370D01*
X116593Y54970D01*
X117193Y55470D01*
X117993Y55670D01*
X118693Y55570D01*
X119193Y55370D01*
X119693Y54970D01*
G01X123093Y50170D02*
X123793Y49770D01*
X124593Y49670D01*
X125293Y49770D01*
X125893Y50270D01*
X126293Y50970D01*
Y55670D01*
G01Y54870D02*
X125893Y55270D01*
X125293Y55570D01*
X124593Y55670D01*
X123793Y55470D01*
X123293Y55070D01*
X122893Y54370D01*
X122693Y53670D01*
X122793Y53070D01*
X123193Y52370D01*
X123793Y51870D01*
X124593Y51670D01*
X125193Y51770D01*
X125893Y52170D01*
X126293Y52570D01*
G01X129593Y54370D02*
X132793D01*
X132493Y55070D01*
X131993Y55470D01*
X131293Y55670D01*
X130593Y55570D01*
X129993Y55270D01*
X129593Y54570D01*
X129393Y53970D01*
Y53370D01*
X129593Y52770D01*
X130093Y52170D01*
X130693Y51770D01*
X131393Y51670D01*
X132093Y51870D01*
X132793Y52470D01*
G01X136293Y51670D02*
Y55670D01*
G01Y54870D02*
X136793Y55270D01*
X137293Y55570D01*
X137993Y55670D01*
X138493Y55570D01*
X139093Y55270D01*
G01X148893Y51670D02*
Y57670D01*
X151393D01*
X152193Y57370D01*
X152693Y56970D01*
X152893Y56170D01*
X152693Y55370D01*
X152093Y54870D01*
X151393Y54570D01*
X148893D01*
G01X151393D02*
X152893Y51670D01*
G01X157493Y55670D02*
Y51670D01*
G01Y57270D02*
X157293Y57370D01*
Y57570D01*
X157493Y57670D01*
X157693Y57570D01*
Y57370D01*
X157493Y57270D01*
G01X162593Y52370D02*
X163093Y51970D01*
X163793Y51670D01*
X164393D01*
X164993Y51870D01*
X165393Y52170D01*
X165593Y52570D01*
X165493Y53170D01*
X165093Y53470D01*
X163293Y54070D01*
X162893Y54770D01*
X163093Y55270D01*
X163493Y55570D01*
X164093Y55670D01*
X164693Y55570D01*
X165293Y55270D01*
G01X169193Y54370D02*
X172393D01*
X172093Y55070D01*
X171593Y55470D01*
X170893Y55670D01*
X170193Y55570D01*
X169593Y55270D01*
X169193Y54570D01*
X168993Y53970D01*
Y53370D01*
X169193Y52770D01*
X169693Y52170D01*
X170293Y51770D01*
X170993Y51670D01*
X171693Y51870D01*
X172393Y52470D01*
G01X175893Y51670D02*
Y55670D01*
G01Y54870D02*
X176393Y55270D01*
X176893Y55570D01*
X177593Y55670D01*
X178093Y55570D01*
X178693Y55270D01*
G01X192693Y57170D02*
X192093Y57470D01*
X191393Y57670D01*
X190593D01*
X189693Y57370D01*
X188993Y56870D01*
X188493Y56270D01*
X188093Y55270D01*
X187993Y54370D01*
X188193Y53470D01*
X188493Y52870D01*
X189093Y52270D01*
X189793Y51870D01*
X190493Y51670D01*
X191193D01*
X191893Y51870D01*
X192493Y52170D01*
X192993Y52570D01*
G01X198893Y51670D02*
Y55670D01*
G01Y54970D02*
X198493Y55370D01*
X197893Y55570D01*
X197193Y55670D01*
X196493Y55470D01*
X195893Y55070D01*
X195493Y54470D01*
X195293Y53670D01*
X195493Y52870D01*
X195893Y52270D01*
X196493Y51870D01*
X197193Y51670D01*
X197893Y51770D01*
X198493Y52070D01*
X198893Y52470D01*
G01X202293Y51670D02*
Y55670D01*
G01Y54870D02*
X202793Y55270D01*
X203293Y55570D01*
X203993Y55670D01*
X204493Y55570D01*
X205093Y55270D01*
G01X212093Y57670D02*
Y51670D01*
G01Y52570D02*
X211693Y52070D01*
X211093Y51770D01*
X210393Y51670D01*
X209593Y51870D01*
X208993Y52370D01*
X208593Y52970D01*
X208493Y53670D01*
X208593Y54370D01*
X208993Y54970D01*
X209593Y55470D01*
X210393Y55670D01*
X211093Y55570D01*
X211593Y55370D01*
X212093Y54970D01*
G01X312910Y28570D02*
Y34570D01*
X315510Y29570D01*
X318110Y34570D01*
Y28570D01*
G01X322110Y28370D02*
X321910Y28470D01*
Y28670D01*
X322110Y28770D01*
X322310Y28670D01*
Y28470D01*
X322110Y28370D01*
G01X327510Y34570D02*
X329910D01*
G01X328710D02*
Y28570D01*
G01X327510D02*
X329910D01*
G01X335310Y28370D02*
X335110Y28470D01*
Y28670D01*
X335310Y28770D01*
X335510Y28670D01*
Y28470D01*
X335310Y28370D01*
G01X341910Y34570D02*
Y28570D01*
G01X339610Y34570D02*
X344210D01*
G01X348510Y28370D02*
X348310Y28470D01*
Y28670D01*
X348510Y28770D01*
X348710Y28670D01*
Y28470D01*
X348510Y28370D01*
M02*
